G04 ================== begin FILE IDENTIFICATION RECORD ==================*
G04 Layout Name:  D:/<user>/Wistron_project/16318-2/gbr/16318-2.brd*
G04 Film Name:    DP_REF_L6*
G04 File Format:  Gerber RS274X*
G04 File Origin:  Cadence Allegro 16.5-S056*
G04 Origin Date:  Mon Aug 07 11:10:00 2017*
G04 *
G04 Layer:  BOARD GEOMETRY/DP_REF_L6_TBL*
G04 Layer:  BOARD GEOMETRY/DP_REF_L6_L6*
G04 Layer:  BOARD GEOMETRY/PANEL_OUTLINE*
G04 *
G04 Offset:    (0.00 0.00)*
G04 Mirror:    No*
G04 Mode:      Positive*
G04 Rotation:  0*
G04 FullContactRelief:  No*
G04 UndefLineWidth:     6.00*
G04 ================== end FILE IDENTIFICATION RECORD ====================*
%FSLAX35Y35*MOIN*%
%IR0*IPPOS*OFA0.00000B0.00000*MIA0B0*SFA1.00000B1.00000*%
%ADD10C,.02*%
%ADD11C,.004*%
%ADD12C,.006*%
%ADD13C,.0055*%
G75*
%LPD*%
G75*
G54D10*
G01X975497Y625480D02*
X1762997D01*
G01X975497Y729430D02*
Y625480D01*
G01Y694780D02*
X1762997D01*
G01X975497Y660130D02*
X1762997D01*
G01X975497Y729430D02*
X1762997D01*
G01X1150497D02*
Y625480D01*
G01X1447997Y729430D02*
Y625480D01*
G01X1552997Y729430D02*
Y625480D01*
G01X1762997Y729430D02*
Y625480D01*
G54D11*
G01X633425Y126921D02*
X649169Y137146D01*
G01X634293Y126053D02*
X649630Y136013D01*
G01X629485Y120856D02*
X633425Y126921D01*
G01X630685Y120500D02*
X634293Y126053D01*
G01X629485Y118921D02*
Y120856D01*
G01X630685Y118423D02*
Y120500D01*
G01X628710Y118147D02*
X629485Y118921D01*
G01X629434Y117172D02*
X630685Y118423D01*
G01X628514Y118041D02*
X628710Y118147D01*
G01X629081Y116983D02*
X629434Y117172D01*
G01X634293Y126053D02*
X649630Y136013D01*
G01X633425Y126921D02*
X649169Y137146D01*
G01X630685Y120500D02*
X634293Y126053D01*
G01X629485Y120856D02*
X633425Y126921D01*
G01X630685Y118423D02*
Y120500D01*
G01X629485Y118921D02*
Y120856D01*
G01X629434Y117172D02*
X630685Y118423D01*
G01X628710Y118147D02*
X629485Y118921D01*
G01X629081Y116983D02*
X629434Y117172D01*
G01X628514Y118041D02*
X628710Y118147D01*
G01X662749Y124244D02*
X683278Y138091D01*
G01X662749Y124244D02*
X683278Y138091D01*
G01X662749Y124244D02*
X683278Y138091D01*
G01X662749Y124244D02*
X683278Y138091D01*
G01X662749Y124244D02*
X683278Y138091D01*
G01X662749Y124244D02*
X683278Y138091D01*
G01X662749Y124244D02*
X683278Y138091D01*
G01X662749Y124244D02*
X683278Y138091D01*
G01X662749Y124244D02*
X683278Y138091D01*
G01X667837Y130029D02*
X668878Y129827D01*
G01X662749Y124244D02*
X683278Y138091D01*
G01X662280Y125376D02*
X666640Y128317D01*
G01X662749Y124244D02*
X683278Y138091D01*
G01X656520Y124256D02*
X662280Y125376D01*
G01X641676Y120147D02*
X662749Y124244D01*
G01X652692Y123512D02*
X653870Y123741D01*
G01X641676Y120147D02*
X662749Y124244D01*
G01X648864Y122768D02*
X650042Y122997D01*
G01X641676Y120147D02*
X662749Y124244D01*
G01X645035Y122023D02*
X646213Y122252D01*
G01X641676Y120147D02*
X662749Y124244D01*
G01X641207Y121279D02*
X642385Y121508D01*
G01X641676Y120147D02*
X662749Y124244D01*
G01X639882Y120385D02*
X641207Y121279D01*
G01X640650Y119454D02*
X641676Y120147D01*
G01X637730Y118232D02*
X639882Y120385D01*
G01X638457Y117260D02*
X640650Y119454D01*
G01X637550Y118134D02*
X637730Y118232D01*
G01X638111Y117072D02*
X638457Y117260D01*
G01X637500Y118109D02*
X637550Y118134D01*
G01X638111Y117072D02*
X638457Y117260D01*
G01X662749Y124244D02*
X683278Y138091D01*
G01X667837Y130029D02*
X668878Y129827D01*
G01X662280Y125376D02*
X666640Y128317D01*
G01X641676Y120147D02*
X662749Y124244D01*
G01X656520Y124256D02*
X662280Y125376D01*
G01X652692Y123512D02*
X653870Y123741D01*
G01X648864Y122768D02*
X650042Y122997D01*
G01X645035Y122023D02*
X646213Y122252D01*
G01X641207Y121279D02*
X642385Y121508D01*
G01X640650Y119454D02*
X641676Y120147D01*
G01X639882Y120385D02*
X641207Y121279D01*
G01X638457Y117260D02*
X640650Y119454D01*
G01X637730Y118232D02*
X639882Y120385D01*
G01X638111Y117072D02*
X638457Y117260D01*
G01X637550Y118134D02*
X637730Y118232D01*
G01X637500Y118109D02*
X637550Y118134D01*
G01X653519Y112347D02*
X687918Y135279D01*
G01X653519Y112347D02*
X687918Y135279D01*
G01X653519Y112347D02*
X687918Y135279D01*
G01X653519Y112347D02*
X687918Y135279D01*
G01X653519Y112347D02*
X687918Y135279D01*
G01X666031Y122131D02*
X674470Y127757D01*
G01X653519Y112347D02*
X687918Y135279D01*
G01X662786Y119968D02*
X663785Y120633D01*
G01X653519Y112347D02*
X687918Y135279D01*
G01X659541Y117805D02*
X660540Y118470D01*
G01X653519Y112347D02*
X687918Y135279D01*
G01X656296Y115641D02*
X657295Y116307D01*
G01X653519Y112347D02*
X687918Y135279D01*
G01X653051Y113478D02*
X654049Y114144D01*
G01X653519Y112347D02*
X687918Y135279D01*
G01X633160Y109502D02*
X653051Y113478D01*
G01X633752Y108395D02*
X653519Y112347D01*
G01X629685Y106026D02*
X633160Y109502D01*
G01X630885Y105528D02*
X633752Y108395D01*
G01X629685Y104160D02*
Y106026D01*
G01X630885Y103662D02*
Y105528D01*
G01X628712Y103188D02*
X629685Y104160D01*
G01X629434Y102211D02*
X630885Y103662D01*
G01X628514Y103080D02*
X628712Y103188D01*
G01X629081Y102022D02*
X629434Y102211D01*
G01X653519Y112347D02*
X687918Y135279D01*
G01X666031Y122131D02*
X674470Y127757D01*
G01X662786Y119968D02*
X663785Y120633D01*
G01X659541Y117805D02*
X660540Y118470D01*
G01X656296Y115641D02*
X657295Y116307D01*
G01X653051Y113478D02*
X654049Y114144D01*
G01X633752Y108395D02*
X653519Y112347D01*
G01X633160Y109502D02*
X653051Y113478D01*
G01X630885Y105528D02*
X633752Y108395D01*
G01X629685Y106026D02*
X633160Y109502D01*
G01X630885Y103662D02*
Y105528D01*
G01X629685Y104160D02*
Y106026D01*
G01X629434Y102211D02*
X630885Y103662D01*
G01X628712Y103188D02*
X629685Y104160D01*
G01X629081Y102022D02*
X629434Y102211D01*
G01X628514Y103080D02*
X628712Y103188D01*
G01X656157Y107960D02*
X692939Y132483D01*
G01X656157Y107960D02*
X692939Y132483D01*
G01X656157Y107960D02*
X692939Y132483D01*
G01X656157Y107960D02*
X692939Y132483D01*
G01X656157Y107960D02*
X692939Y132483D01*
G01X656157Y107960D02*
X692939Y132483D01*
G01X667628Y117953D02*
X668668Y117745D01*
G01X656157Y107960D02*
X692939Y132483D01*
G01X665423Y115581D02*
X666421Y116247D01*
G01X656157Y107960D02*
X692939Y132483D01*
G01X655688Y109091D02*
X663176Y114083D01*
G01X656157Y107960D02*
X692939Y132483D01*
G01X654511Y108856D02*
X655688Y109091D01*
G01X656157Y107960D02*
X692939Y132483D01*
G01X640630Y104854D02*
X656157Y107960D01*
G01X650687Y108091D02*
X651864Y108326D01*
G01X640630Y104854D02*
X656157Y107960D01*
G01X646863Y107326D02*
X648040Y107561D01*
G01X640630Y104854D02*
X656157Y107960D01*
G01X639906Y105934D02*
X644215Y106796D01*
G01X640630Y104854D02*
X656157Y107960D01*
G01X638354Y103604D02*
X639906Y105934D01*
G01X639186Y102686D02*
X640630Y104854D01*
G01X637373Y103079D02*
X638354Y103604D01*
G01X637941Y102021D02*
X639186Y102686D01*
G01X656157Y107960D02*
X692939Y132483D01*
G01X667628Y117953D02*
X668668Y117745D01*
G01X665423Y115581D02*
X666421Y116247D01*
G01X655688Y109091D02*
X663176Y114083D01*
G01X654511Y108856D02*
X655688Y109091D01*
G01X640630Y104854D02*
X656157Y107960D01*
G01X654511Y108856D02*
X655688Y109091D01*
G01X650687Y108091D02*
X651864Y108326D01*
G01X646863Y107326D02*
X648040Y107561D01*
G01X639906Y105934D02*
X644215Y106796D01*
G01X639186Y102686D02*
X640630Y104854D01*
G01X638354Y103604D02*
X639906Y105934D01*
G01X637941Y102021D02*
X639186Y102686D01*
G01X637373Y103079D02*
X638354Y103604D01*
G01X649630Y136013D02*
X814175Y168831D01*
G01X649630Y136013D02*
X814175Y168831D01*
G01X649630Y136013D02*
X814175Y168831D01*
G01X649630Y136013D02*
X814175Y168831D01*
G01X649630Y136013D02*
X814175Y168831D01*
G01X649630Y136013D02*
X814175Y168831D01*
G01X664468Y140197D02*
X729431Y153153D01*
G01X649630Y136013D02*
X814175Y168831D01*
G01X660643Y139434D02*
X661820Y139669D01*
G01X649630Y136013D02*
X814175Y168831D01*
G01X656818Y138672D02*
X657995Y138906D01*
G01X649630Y136013D02*
X814175Y168831D01*
G01X649170Y137146D02*
X654171Y138143D01*
G01X649630Y136013D02*
X814175Y168831D01*
G01X649630Y136013D02*
X814175Y168831D01*
G01X664468Y140197D02*
X729431Y153153D01*
G01X660643Y139434D02*
X661820Y139669D01*
G01X656818Y138672D02*
X657995Y138906D01*
G01X649170Y137146D02*
X654171Y138143D01*
G01X716338Y128537D02*
X722783Y134983D01*
G01X709485Y119986D02*
X723375Y133876D01*
G01X713580Y125780D02*
X714429Y126628D01*
G01X709485Y119986D02*
X723375Y133876D01*
G01X708285Y120484D02*
X711671Y123870D01*
G01X709485Y119986D02*
X723375Y133876D01*
G01X708285Y118906D02*
Y120484D01*
G01X709485Y118408D02*
Y119986D01*
G01X707609Y118231D02*
X708285Y118906D01*
G01X708332Y117255D02*
X709485Y118408D01*
G01X707255Y118041D02*
X707609Y118231D01*
G01X707822Y116983D02*
X708332Y117255D01*
G01X709485Y119986D02*
X723375Y133876D01*
G01X716338Y128537D02*
X722783Y134983D01*
G01X713580Y125780D02*
X714429Y126628D01*
G01X708285Y120484D02*
X711671Y123870D01*
G01X709485Y118408D02*
Y119986D01*
G01X708285Y118906D02*
Y120484D01*
G01X708332Y117255D02*
X709485Y118408D01*
G01X707609Y118231D02*
X708285Y118906D01*
G01X707822Y116983D02*
X708332Y117255D01*
G01X707255Y118041D02*
X707609Y118231D01*
G01X725533Y125278D02*
X739190Y134383D01*
G01X720249Y120313D02*
X739658Y133252D01*
G01X719484Y121246D02*
X723286Y123781D01*
G01X720249Y120313D02*
X739658Y133252D01*
G01X716467Y118230D02*
X719484Y121246D01*
G01X717190Y117254D02*
X720249Y120313D01*
G01X716448Y118219D02*
X716467Y118230D01*
G01X716956Y117130D02*
X717190Y117254D01*
G01X716390Y118188D02*
X716445Y118217D01*
G01X716956Y117130D02*
X717190Y117254D01*
G01X716374Y118180D02*
X716390Y118188D01*
G01X716956Y117130D02*
X717190Y117254D01*
G01X716116Y118042D02*
X716374Y118180D01*
G01X716956Y117130D02*
X717190Y117254D01*
G01X716948Y117125D02*
X716953Y117128D01*
G01X716944Y117123D02*
X716948Y117125D01*
G01X716938Y117118D02*
X716945Y117122D01*
G01X716857Y117076D02*
X716938Y117118D01*
G01X716681Y116982D02*
X716857Y117076D01*
G01X720249Y120313D02*
X739658Y133252D01*
G01X725533Y125278D02*
X739190Y134383D01*
G01X719484Y121246D02*
X723286Y123781D01*
G01X717190Y117254D02*
X720249Y120313D01*
G01X716467Y118230D02*
X719484Y121246D01*
G01X716956Y117130D02*
X717190Y117254D01*
G01X716448Y118219D02*
X716467Y118230D01*
G01X716390Y118188D02*
X716445Y118217D01*
G01X716374Y118180D02*
X716390Y118188D01*
G01X716116Y118042D02*
X716374Y118180D01*
G01X716948Y117125D02*
X716953Y117128D01*
G01X716116Y118042D02*
X716374Y118180D01*
G01X716944Y117123D02*
X716948Y117125D01*
G01X716116Y118042D02*
X716374Y118180D01*
G01X716938Y117118D02*
X716945Y117122D01*
G01X716116Y118042D02*
X716374Y118180D01*
G01X716857Y117076D02*
X716938Y117118D01*
G01X716116Y118042D02*
X716374Y118180D01*
G01X716681Y116982D02*
X716857Y117076D01*
G01X716116Y118042D02*
X716374Y118180D01*
G01X719930Y111997D02*
X750168Y132156D01*
G01X720398Y110866D02*
X750637Y131025D01*
G01X713765Y110765D02*
X719930Y111997D01*
G01X714357Y109659D02*
X720398Y110866D01*
G01X709400Y106400D02*
X713765Y110765D01*
G01X710600Y105902D02*
X714357Y109659D01*
G01X709400Y105061D02*
Y106400D01*
G01X710600Y104563D02*
Y105902D01*
G01X707608Y103269D02*
X709400Y105061D01*
G01X708332Y102294D02*
X710600Y104563D01*
G01X707255Y103080D02*
X707608Y103269D01*
G01X707822Y102022D02*
X708332Y102294D01*
G01X720398Y110866D02*
X750637Y131025D01*
G01X719930Y111997D02*
X750168Y132156D01*
G01X714357Y109659D02*
X720398Y110866D01*
G01X713765Y110765D02*
X719930Y111997D01*
G01X710600Y105902D02*
X714357Y109659D01*
G01X709400Y106400D02*
X713765Y110765D01*
G01X710600Y104563D02*
Y105902D01*
G01X709400Y105061D02*
Y106400D01*
G01X708332Y102294D02*
X710600Y104563D01*
G01X707608Y103269D02*
X709400Y105061D01*
G01X707822Y102022D02*
X708332Y102294D01*
G01X707255Y103080D02*
X707608Y103269D01*
G01X716431Y103249D02*
X716116Y103081D01*
G01X716996Y102188D02*
X716681Y102021D01*
G01X717008Y102195D02*
X717001Y102191D01*
G01X717190Y102293D02*
X717011Y102197D01*
G01X716441Y103254D02*
X716431Y103249D01*
G01X716996Y102188D02*
X716681Y102021D01*
G01X716466Y103268D02*
X716441Y103254D01*
G01X716996Y102188D02*
X716681Y102021D01*
G01X722293Y109094D02*
X716466Y103268D01*
G01X723058Y108161D02*
X717190Y102293D01*
G01X750805Y128101D02*
X722293Y109094D01*
G01X751273Y126970D02*
X723058Y108161D01*
G01X716996Y102188D02*
X716681Y102021D01*
G01X716431Y103249D02*
X716116Y103081D01*
G01X716441Y103254D02*
X716431Y103249D01*
G01X716466Y103268D02*
X716441Y103254D01*
G01X717008Y102195D02*
X717001Y102191D01*
G01X716431Y103249D02*
X716116Y103081D01*
G01X717190Y102293D02*
X717011Y102197D01*
G01X716431Y103249D02*
X716116Y103081D01*
G01X723058Y108161D02*
X717190Y102293D01*
G01X722293Y109094D02*
X716466Y103268D01*
G01X751273Y126970D02*
X723058Y108161D01*
G01X750805Y128101D02*
X722293Y109094D01*
G01X672111Y132007D02*
X673106Y132678D01*
G01X671070Y132210D02*
X672111Y132007D01*
G01X668878Y129827D02*
X669873Y130498D01*
G01X672111Y132007D02*
X673106Y132678D01*
G01X671070Y132210D02*
X672111Y132007D01*
G01X668878Y129827D02*
X669873Y130498D01*
G01X683206Y133581D02*
X684205Y134247D01*
G01X679961Y131418D02*
X680960Y132083D01*
G01X676716Y129255D02*
X677715Y129920D01*
G01X683206Y133581D02*
X684205Y134247D01*
G01X679961Y131418D02*
X680960Y132083D01*
G01X676716Y129255D02*
X677715Y129920D01*
G01X692471Y133614D02*
X817346Y158573D01*
G01X692939Y132483D02*
X817814Y157442D01*
G01X691473Y132948D02*
X692471Y133614D01*
G01X690432Y133156D02*
X691473Y132948D01*
G01X688228Y130785D02*
X689226Y131451D01*
G01X684983Y128622D02*
X685981Y129287D01*
G01X681738Y126458D02*
X682736Y127124D01*
G01X668668Y117745D02*
X679491Y124960D01*
G01X692939Y132483D02*
X817814Y157442D01*
G01X692471Y133614D02*
X817346Y158573D01*
G01X691473Y132948D02*
X692471Y133614D01*
G01X690432Y133156D02*
X691473Y132948D01*
G01X688228Y130785D02*
X689226Y131451D01*
G01X684983Y128622D02*
X685981Y129287D01*
G01X681738Y126458D02*
X682736Y127124D01*
G01X668668Y117745D02*
X679491Y124960D01*
G01X723375Y133876D02*
X816338Y152467D01*
G01X723375Y133876D02*
X816338Y152467D01*
G01X723375Y133876D02*
X816338Y152467D01*
G01X723375Y133876D02*
X816338Y152467D01*
G01X723375Y133876D02*
X816338Y152467D01*
G01X732225Y136870D02*
X733402Y137106D01*
G01X723375Y133876D02*
X816338Y152467D01*
G01X728401Y136106D02*
X729577Y136341D01*
G01X723375Y133876D02*
X816338Y152467D01*
G01X722783Y134983D02*
X725753Y135576D01*
G01X723375Y133876D02*
X816338Y152467D01*
G01X723375Y133876D02*
X816338Y152467D01*
G01X732225Y136870D02*
X733402Y137106D01*
G01X728401Y136106D02*
X729577Y136341D01*
G01X722783Y134983D02*
X725753Y135576D01*
G01X732079Y153681D02*
X733256Y153916D01*
G01X732079Y153681D02*
X733256Y153916D01*
G01X682806Y139221D02*
X814333Y165527D01*
G01X683278Y138091D02*
X814802Y164397D01*
G01X681811Y138550D02*
X682806Y139221D01*
G01X680770Y138752D02*
X681811Y138550D01*
G01X678578Y136369D02*
X679573Y137040D01*
G01X677537Y136571D02*
X678578Y136369D01*
G01X675345Y134188D02*
X676340Y134859D01*
G01X674303Y134391D02*
X675345Y134188D01*
G01X683278Y138091D02*
X814802Y164397D01*
G01X682806Y139221D02*
X814333Y165527D01*
G01X681811Y138550D02*
X682806Y139221D01*
G01X680770Y138752D02*
X681811Y138550D01*
G01X678578Y136369D02*
X679573Y137040D01*
G01X677537Y136571D02*
X678578Y136369D01*
G01X675345Y134188D02*
X676340Y134859D01*
G01X674303Y134391D02*
X675345Y134188D01*
G01X687450Y136410D02*
X817208Y162361D01*
G01X687918Y135279D02*
X817677Y161231D01*
G01X686452Y135744D02*
X687450Y136410D01*
G01X685411Y135952D02*
X686452Y135744D01*
G01X687918Y135279D02*
X817677Y161231D01*
G01X687450Y136410D02*
X817208Y162361D01*
G01X686452Y135744D02*
X687450Y136410D01*
G01X685411Y135952D02*
X686452Y135744D01*
G01X739658Y133252D02*
X816308Y148581D01*
G01X739658Y133252D02*
X816308Y148581D01*
G01X739658Y133252D02*
X816308Y148581D01*
G01X739658Y133252D02*
X816308Y148581D01*
G01X739658Y133252D02*
X816308Y148581D01*
G01X739658Y133252D02*
X816308Y148581D01*
G01X739658Y133252D02*
X816308Y148581D01*
G01X739658Y133252D02*
X816308Y148581D01*
G01X739658Y133252D02*
X816308Y148581D01*
G01X739658Y133252D02*
X816308Y148581D01*
G01X750637Y131025D02*
X815483Y144001D01*
G01X750637Y131025D02*
X815483Y144001D01*
G01X750637Y131025D02*
X815483Y144001D01*
G01X750637Y131025D02*
X815483Y144001D01*
G01X750637Y131025D02*
X815483Y144001D01*
G01X750637Y131025D02*
X815483Y144001D01*
G01X757816Y133687D02*
X758993Y133922D01*
G01X750637Y131025D02*
X815483Y144001D01*
G01X753992Y132921D02*
X755169Y133157D01*
G01X750637Y131025D02*
X815483Y144001D01*
G01X750168Y132156D02*
X751345Y132391D01*
G01X750637Y131025D02*
X815483Y144001D01*
G01X750637Y131025D02*
X815483Y144001D01*
G01X757816Y133687D02*
X758993Y133922D01*
G01X753992Y132921D02*
X755169Y133157D01*
G01X750168Y132156D02*
X751345Y132391D01*
G01X751982Y128336D02*
X750805Y128101D01*
G01X815360Y139787D02*
X751273Y126970D01*
G01X755806Y129101D02*
X754629Y128866D01*
G01X815360Y139787D02*
X751273Y126970D01*
G01X759630Y129866D02*
X758454Y129631D01*
G01X815360Y139787D02*
X751273Y126970D01*
G01X763454Y130631D02*
X762278Y130396D01*
G01X815360Y139787D02*
X751273Y126970D01*
G01X799099Y137760D02*
X766102Y131160D01*
G01X815360Y139787D02*
X751273Y126970D01*
G01X815360Y139787D02*
X751273Y126970D01*
G01X815360Y139787D02*
X751273Y126970D01*
G01X815360Y139787D02*
X751273Y126970D01*
G01X815360Y139787D02*
X751273Y126970D01*
G01X815360Y139787D02*
X751273Y126970D01*
G01X751982Y128336D02*
X750805Y128101D01*
G01X755806Y129101D02*
X754629Y128866D01*
G01X759630Y129866D02*
X758454Y129631D01*
G01X763454Y130631D02*
X762278Y130396D01*
G01X799099Y137760D02*
X766102Y131160D01*
G01X736049Y137635D02*
X800572Y150539D01*
G01X736049Y137635D02*
X800572Y150539D01*
G01X754487Y137442D02*
X800543Y146653D01*
G01X750663Y136677D02*
X751840Y136913D01*
G01X746839Y135913D02*
X748015Y136148D01*
G01X743014Y135148D02*
X744191Y135383D01*
G01X739190Y134383D02*
X740367Y134618D01*
G01X754487Y137442D02*
X800543Y146653D01*
G01X750663Y136677D02*
X751840Y136913D01*
G01X746839Y135913D02*
X748015Y136148D01*
G01X743014Y135148D02*
X744191Y135383D01*
G01X739190Y134383D02*
X740367Y134618D01*
G01X765465Y135217D02*
X799717Y142071D01*
G01X761641Y134452D02*
X762817Y134687D01*
G01X765465Y135217D02*
X799717Y142071D01*
G01X761641Y134452D02*
X762817Y134687D01*
G01X739728Y155207D02*
X799082Y167045D01*
G01X735904Y154444D02*
X737080Y154679D01*
G01X739728Y155207D02*
X799082Y167045D01*
G01X735904Y154444D02*
X737080Y154679D01*
G01X853016Y185142D02*
X860842Y224287D01*
G01X854147Y184674D02*
X862066Y224287D01*
G01X844881Y172940D02*
X853016Y185142D01*
G01X845747Y172074D02*
X854147Y184674D01*
G01X815869Y153598D02*
X844881Y172940D01*
G01X816338Y152467D02*
X845747Y172074D01*
G01X814692Y153363D02*
X815869Y153598D01*
G01X816338Y152467D02*
X845747Y172074D01*
G01X810868Y152598D02*
X812045Y152833D01*
G01X807044Y151833D02*
X808220Y152068D01*
G01X803219Y151068D02*
X804396Y151304D01*
G01X854147Y184674D02*
X862066Y224287D01*
G01X853016Y185142D02*
X860842Y224287D01*
G01X845747Y172074D02*
X854147Y184674D01*
G01X844881Y172940D02*
X853016Y185142D01*
G01X816338Y152467D02*
X845747Y172074D01*
G01X815869Y153598D02*
X844881Y172940D01*
G01X814692Y153363D02*
X815869Y153598D01*
G01X814692Y153363D02*
X815869Y153598D01*
G01X810868Y152598D02*
X812045Y152833D01*
G01X807044Y151833D02*
X808220Y152068D01*
G01X803219Y151068D02*
X804396Y151304D01*
G01X856917Y184102D02*
X865685Y227951D01*
G01X858048Y183633D02*
X866909Y227951D01*
G01X848509Y171491D02*
X856917Y184102D01*
G01X849375Y170625D02*
X858048Y183633D01*
G01X815840Y149712D02*
X848509Y171491D01*
G01X816308Y148581D02*
X849375Y170625D01*
G01X814663Y149477D02*
X815840Y149712D01*
G01X816308Y148581D02*
X849375Y170625D01*
G01X810839Y148712D02*
X812016Y148947D01*
G01X807015Y147947D02*
X808191Y148182D01*
G01X803190Y147182D02*
X804367Y147418D01*
G01X858048Y183633D02*
X866909Y227951D01*
G01X856917Y184102D02*
X865685Y227951D01*
G01X849375Y170625D02*
X858048Y183633D01*
G01X848509Y171491D02*
X856917Y184102D01*
G01X816308Y148581D02*
X849375Y170625D01*
G01X815840Y149712D02*
X848509Y171491D01*
G01X814663Y149477D02*
X815840Y149712D01*
G01X814663Y149477D02*
X815840Y149712D01*
G01X810839Y148712D02*
X812016Y148947D01*
G01X807015Y147947D02*
X808191Y148182D01*
G01X803190Y147182D02*
X804367Y147418D01*
G01X860506Y182674D02*
X869664Y228461D01*
G01X861637Y182205D02*
X870888Y228461D01*
G01X851846Y169685D02*
X860506Y182674D01*
G01X852712Y168819D02*
X861637Y182205D01*
G01X815014Y145132D02*
X851846Y169685D01*
G01X815483Y144001D02*
X852712Y168819D01*
G01X813837Y144897D02*
X815014Y145132D01*
G01X815483Y144001D02*
X852712Y168819D01*
G01X810013Y144131D02*
X811190Y144367D01*
G01X806189Y143366D02*
X807366Y143601D01*
G01X802365Y142601D02*
X803541Y142836D01*
G01X861637Y182205D02*
X870888Y228461D01*
G01X860506Y182674D02*
X869664Y228461D01*
G01X852712Y168819D02*
X861637Y182205D01*
G01X851846Y169685D02*
X860506Y182674D01*
G01X815483Y144001D02*
X852712Y168819D01*
G01X815014Y145132D02*
X851846Y169685D01*
G01X813837Y144897D02*
X815014Y145132D01*
G01X813837Y144897D02*
X815014Y145132D01*
G01X810013Y144131D02*
X811190Y144367D01*
G01X806189Y143366D02*
X807366Y143601D01*
G01X802365Y142601D02*
X803541Y142836D01*
G01X802924Y138525D02*
X801747Y138289D01*
G01X806748Y139289D02*
X805571Y139054D01*
G01X810572Y140054D02*
X809396Y139819D01*
G01X814892Y140918D02*
X813220Y140584D01*
G01X854841Y167550D02*
X814892Y140918D01*
G01X855707Y166684D02*
X815360Y139787D01*
G01X864744Y182407D02*
X854841Y167550D01*
G01X865875Y181939D02*
X855707Y166684D01*
G01X802924Y138525D02*
X801747Y138289D01*
G01X806748Y139289D02*
X805571Y139054D01*
G01X810572Y140054D02*
X809396Y139819D01*
G01X814892Y140918D02*
X813220Y140584D01*
G01X855707Y166684D02*
X815360Y139787D01*
G01X854841Y167550D02*
X814892Y140918D01*
G01X865875Y181939D02*
X855707Y166684D01*
G01X864744Y182407D02*
X854841Y167550D01*
G01X837324Y189586D02*
X841458Y210275D01*
G01X838455Y189118D02*
X842682Y210275D01*
G01X832666Y182601D02*
X837324Y189586D01*
G01X833532Y181735D02*
X838455Y189118D01*
G01X813707Y169962D02*
X832666Y182601D01*
G01X814175Y168831D02*
X833532Y181735D01*
G01X809380Y169099D02*
X813707Y169962D01*
G01X805555Y168336D02*
X806732Y168571D01*
G01X801730Y167573D02*
X802907Y167808D01*
G01X838455Y189118D02*
X842682Y210275D01*
G01X837324Y189586D02*
X841458Y210275D01*
G01X833532Y181735D02*
X838455Y189118D01*
G01X832666Y182601D02*
X837324Y189586D01*
G01X814175Y168831D02*
X833532Y181735D01*
G01X813707Y169962D02*
X832666Y182601D01*
G01X809380Y169099D02*
X813707Y169962D01*
G01X805555Y168336D02*
X806732Y168571D01*
G01X801730Y167573D02*
X802907Y167808D01*
G01X840926Y188276D02*
X845976Y214256D01*
G01X842058Y187807D02*
X847200Y214259D01*
G01X834799Y179193D02*
X840926Y188276D01*
G01X835662Y178326D02*
X842058Y187807D01*
G01X814333Y165527D02*
X834799Y179193D01*
G01X814802Y164397D02*
X835662Y178326D01*
G01X842058Y187807D02*
X847200Y214259D01*
G01X840926Y188276D02*
X845976Y214256D01*
G01X835662Y178326D02*
X842058Y187807D01*
G01X834799Y179193D02*
X840926Y188276D01*
G01X814802Y164397D02*
X835662Y178326D01*
G01X814333Y165527D02*
X834799Y179193D01*
G01X845231Y187804D02*
X850680Y215835D01*
G01X846363Y187335D02*
X851904Y215838D01*
G01X841101Y181682D02*
X845231Y187804D01*
G01X837835Y174693D02*
X846363Y187335D01*
G01X836972Y175560D02*
X841101Y181681D01*
G01X837835Y174693D02*
X846363Y187335D01*
G01X817208Y162361D02*
X836972Y175560D01*
G01X817677Y161231D02*
X837835Y174693D01*
G01X846363Y187335D02*
X851904Y215838D01*
G01X845231Y187804D02*
X850680Y215835D01*
G01X837835Y174693D02*
X846363Y187335D01*
G01X841101Y181682D02*
X845231Y187804D01*
G01X836972Y175560D02*
X841101Y181681D01*
G01X817677Y161231D02*
X837835Y174693D01*
G01X817208Y162361D02*
X836972Y175560D01*
G01X848882Y186202D02*
X855478Y219183D01*
G01X850013Y185734D02*
X856702Y219183D01*
G01X840955Y174311D02*
X848882Y186202D01*
G01X845918Y179590D02*
X850013Y185734D01*
G01X841821Y173445D02*
X845917Y179590D01*
G01X817346Y158573D02*
X840955Y174311D01*
G01X817814Y157442D02*
X841821Y173445D01*
G01X850013Y185734D02*
X856702Y219183D01*
G01X848882Y186202D02*
X855478Y219183D01*
G01X845918Y179590D02*
X850013Y185734D01*
G01X840955Y174311D02*
X848882Y186202D01*
G01X841821Y173445D02*
X845917Y179590D01*
G01X840955Y174311D02*
X848882Y186202D01*
G01X817814Y157442D02*
X841821Y173445D01*
G01X817346Y158573D02*
X840955Y174311D01*
G01X860842Y224287D02*
X851675Y270127D01*
G01X862066Y224287D02*
X852781Y270719D01*
G01X862066Y224287D02*
X852781Y270719D01*
G01X860842Y224287D02*
X851675Y270127D01*
G01X865685Y227951D02*
X856633Y273214D01*
G01X866909Y227951D02*
X857764Y273683D01*
G01X866909Y227951D02*
X857764Y273683D01*
G01X865685Y227951D02*
X856633Y273214D01*
G01X869664Y228461D02*
X858416Y284682D01*
G01X870888Y228461D02*
X859547Y285151D01*
G01X870888Y228461D02*
X859547Y285151D01*
G01X869664Y228461D02*
X858416Y284682D01*
G01X831588Y249982D02*
X831587D01*
G01X831700Y248396D02*
X832437Y249133D01*
G01X830500Y248894D02*
X831588Y249982D01*
G01X831700Y248396D02*
X832437Y249133D01*
G01X830500Y246402D02*
Y248894D01*
G01X831700Y246900D02*
Y248396D01*
G01X835164Y241738D02*
X830500Y246402D01*
G01X836270Y242330D02*
X831700Y246900D01*
G01X841458Y210275D02*
X835164Y241738D01*
G01X842682Y210275D02*
X836270Y242330D01*
G01X831700Y248396D02*
X832437Y249133D01*
G01X831588Y249982D02*
X831587D01*
G01X830500Y248894D02*
X831588Y249982D01*
G01X831700Y246900D02*
Y248396D01*
G01X830500Y246402D02*
Y248894D01*
G01X836270Y242330D02*
X831700Y246900D01*
G01X835164Y241738D02*
X830500Y246402D01*
G01X842682Y210275D02*
X836270Y242330D01*
G01X841458Y210275D02*
X835164Y241738D01*
G01X831374Y258724D02*
X832251Y259601D01*
G01X832574Y258226D02*
X833100Y258752D01*
G01X831374Y255428D02*
Y258724D01*
G01X832574Y255926D02*
Y258226D01*
G01X839333Y247469D02*
X831374Y255428D01*
G01X840439Y248061D02*
X832574Y255926D01*
G01X845976Y214256D02*
X839333Y247469D01*
G01X847200Y214259D02*
X840439Y248061D01*
G01X832574Y258226D02*
X833100Y258752D01*
G01X831374Y258724D02*
X832251Y259601D01*
G01X832574Y255926D02*
Y258226D01*
G01X831374Y255428D02*
Y258724D01*
G01X840439Y248061D02*
X832574Y255926D01*
G01X839333Y247469D02*
X831374Y255428D01*
G01X847200Y214259D02*
X840439Y248061D01*
G01X845976Y214256D02*
X839333Y247469D01*
G01X838150Y264502D02*
X838900Y265252D01*
G01X836950Y262052D02*
Y265000D01*
G01X838150Y262550D02*
Y264502D01*
G01X842560Y256442D02*
X836950Y262052D01*
G01X843666Y257034D02*
X838150Y262550D01*
G01X846620Y236140D02*
X842560Y256442D01*
G01X851904Y215838D02*
X843666Y257034D01*
G01X850680Y215835D02*
X846620Y236139D01*
G01X851904Y215838D02*
X843666Y257034D01*
G01X838150Y264502D02*
X838900Y265252D01*
G01X838150Y262550D02*
Y264502D01*
G01X836950Y262052D02*
Y265000D01*
G01X843666Y257034D02*
X838150Y262550D01*
G01X842560Y256442D02*
X836950Y262052D01*
G01X851904Y215838D02*
X843666Y257034D01*
G01X846620Y236140D02*
X842560Y256442D01*
G01X850680Y215835D02*
X846620Y236139D01*
G01X846442Y264360D02*
X842774Y268028D01*
G01X855478Y219183D02*
X846442Y264360D01*
G01X856702Y219183D02*
X847548Y264952D01*
G01X846442Y264360D02*
X842774Y268028D01*
G01X856702Y219183D02*
X847548Y264952D01*
G01X855478Y219183D02*
X846442Y264360D01*
G01X840774Y283624D02*
X842051Y284901D01*
G01X841974Y283126D02*
X842900Y284052D01*
G01X840774Y281028D02*
Y283624D01*
G01X841974Y281526D02*
Y283126D01*
G01X851675Y270127D02*
X840774Y281028D01*
G01X852781Y270719D02*
X841974Y281526D01*
G01Y283126D02*
X842900Y284052D01*
G01X840774Y283624D02*
X842051Y284901D01*
G01X841974Y281526D02*
Y283126D01*
G01X840774Y281028D02*
Y283624D01*
G01X852781Y270719D02*
X841974Y281526D01*
G01X851675Y270127D02*
X840774Y281028D01*
G01X846274Y289124D02*
X847551Y290401D01*
G01X847474Y288626D02*
X848400Y289552D01*
G01X846274Y286328D02*
Y289124D01*
G01X847474Y286826D02*
Y288626D01*
G01X851124Y281478D02*
X846274Y286328D01*
G01X852057Y282243D02*
X847474Y286826D01*
G01X853878Y277347D02*
X851124Y281478D01*
G01X857764Y273683D02*
X852057Y282243D01*
G01X856633Y273214D02*
X853878Y277346D01*
G01X857764Y273683D02*
X852057Y282243D01*
G01X847474Y288626D02*
X848400Y289552D01*
G01X846274Y289124D02*
X847551Y290401D01*
G01X847474Y286826D02*
Y288626D01*
G01X846274Y286328D02*
Y289124D01*
G01X852057Y282243D02*
X847474Y286826D01*
G01X851124Y281478D02*
X846274Y286328D01*
G01X857764Y273683D02*
X852057Y282243D01*
G01X853878Y277347D02*
X851124Y281478D01*
G01X856633Y273214D02*
X853878Y277346D01*
G01X852274Y295124D02*
X853551Y296401D01*
G01X853474Y294626D02*
X854400Y295552D01*
G01X852274Y291928D02*
Y295124D01*
G01X853474Y292426D02*
Y294626D01*
G01X856207Y287995D02*
X852274Y291928D01*
G01X857140Y288760D02*
X853474Y292426D01*
G01X857311Y286340D02*
X856207Y287995D01*
G01X859547Y285151D02*
X857140Y288760D01*
G01X858416Y284682D02*
X857311Y286339D01*
G01X859547Y285151D02*
X857140Y288760D01*
G01X853474Y294626D02*
X854400Y295552D01*
G01X852274Y295124D02*
X853551Y296401D01*
G01X853474Y292426D02*
Y294626D01*
G01X852274Y291928D02*
Y295124D01*
G01X857140Y288760D02*
X853474Y292426D01*
G01X856207Y287995D02*
X852274Y291928D01*
G01X859547Y285151D02*
X857140Y288760D01*
G01X857311Y286340D02*
X856207Y287995D01*
G01X858416Y284682D02*
X857311Y286339D01*
G01X862528Y290826D02*
X874480Y231079D01*
G01X863659Y291295D02*
X875704Y231079D01*
G01X857031Y299071D02*
X862528Y290826D01*
G01X857964Y299836D02*
X863659Y291295D01*
G01X847524Y308578D02*
X857031Y299071D01*
G01X848724Y309076D02*
X857964Y299836D01*
G01X847524Y310374D02*
Y308578D01*
G01X848724Y309876D02*
Y309076D01*
G01X849051Y311901D02*
X847524Y310374D01*
G01X849900Y311052D02*
X848724Y309876D01*
G01X863659Y291295D02*
X875704Y231079D01*
G01X862528Y290826D02*
X874480Y231079D01*
G01X857964Y299836D02*
X863659Y291295D01*
G01X857031Y299071D02*
X862528Y290826D01*
G01X848724Y309076D02*
X857964Y299836D01*
G01X847524Y308578D02*
X857031Y299071D01*
G01X848724Y309876D02*
Y309076D01*
G01X847524Y310374D02*
Y308578D01*
G01X849900Y311052D02*
X848724Y309876D01*
G01X849051Y311901D02*
X847524Y310374D01*
G01X836950Y265000D02*
X838051Y266101D01*
G01X836950Y265000D02*
X838051Y266101D01*
G01X842774Y270624D02*
X844051Y271901D01*
G01X843974Y270126D02*
X844900Y271052D01*
G01X842774Y268028D02*
Y270624D01*
G01X843974Y268526D02*
Y270126D01*
G01X847548Y264952D02*
X843974Y268526D01*
G01Y270126D02*
X844900Y271052D01*
G01X842774Y270624D02*
X844051Y271901D01*
G01X843974Y268526D02*
Y270126D01*
G01X842774Y268028D02*
Y270624D01*
G01X847548Y264952D02*
X843974Y268526D01*
G01X874480Y231079D02*
X864744Y182407D01*
G01X875704Y231079D02*
X865875Y181939D01*
G01X875704Y231079D02*
X865875Y181939D01*
G01X874480Y231079D02*
X864744Y182407D01*
G54D12*
G01X6250Y-32800D02*
Y-50300D01*
G01X1228Y-32800D02*
X11272D01*
G01X20038Y-50300D02*
Y-32800D01*
G01Y-41258D02*
X21130Y-39800D01*
X22222Y-38925D01*
X23968Y-38634D01*
X25278Y-38925D01*
X26807Y-40092D01*
X27462Y-41842D01*
Y-50300D01*
G01X41250Y-38634D02*
Y-50300D01*
G01Y-33967D02*
X40813Y-33675D01*
Y-33092D01*
X41250Y-32800D01*
X41687Y-33092D01*
Y-33675D01*
X41250Y-33967D01*
G01X55475Y-48259D02*
X56567Y-49425D01*
X58095Y-50300D01*
X59405D01*
X60715Y-49717D01*
X61588Y-48842D01*
X62025Y-47676D01*
X61807Y-45925D01*
X60933Y-45050D01*
X57003Y-43300D01*
X56130Y-41258D01*
X56567Y-39800D01*
X57440Y-38925D01*
X58750Y-38634D01*
X60060Y-38925D01*
X61370Y-39800D01*
G01X90693Y-54675D02*
X92222Y-55842D01*
X93968Y-56133D01*
X95496Y-55842D01*
X96807Y-54384D01*
X97680Y-52342D01*
Y-38634D01*
G01Y-40967D02*
X96807Y-39800D01*
X95496Y-38925D01*
X93968Y-38634D01*
X92222Y-39217D01*
X91130Y-40383D01*
X90256Y-42425D01*
X89820Y-44467D01*
X90038Y-46217D01*
X90912Y-48259D01*
X92222Y-49717D01*
X93968Y-50300D01*
X95278Y-50008D01*
X96807Y-48842D01*
X97680Y-47676D01*
G01X107975Y-42425D02*
X114962D01*
X114307Y-40383D01*
X113215Y-39217D01*
X111687Y-38634D01*
X110158Y-38925D01*
X108848Y-39800D01*
X107975Y-41842D01*
X107538Y-43592D01*
Y-45342D01*
X107975Y-47092D01*
X109067Y-48842D01*
X110377Y-50008D01*
X111905Y-50300D01*
X113433Y-49717D01*
X114962Y-47967D01*
G01X125693Y-50300D02*
Y-38634D01*
G01Y-40967D02*
X126785Y-39800D01*
X127877Y-38925D01*
X129405Y-38634D01*
X130496Y-38925D01*
X131807Y-39800D01*
G01X142320Y-50300D02*
Y-32800D01*
G01Y-41550D02*
X143412Y-39800D01*
X144722Y-38925D01*
X146032Y-38634D01*
X147996Y-39217D01*
X149307Y-40383D01*
X150180Y-42425D01*
Y-44758D01*
X149743Y-47092D01*
X148870Y-48842D01*
X147342Y-50008D01*
X146032Y-50300D01*
X144722Y-50008D01*
X143412Y-49134D01*
X142320Y-47676D01*
G01X160475Y-42425D02*
X167462D01*
X166807Y-40383D01*
X165715Y-39217D01*
X164187Y-38634D01*
X162658Y-38925D01*
X161348Y-39800D01*
X160475Y-41842D01*
X160038Y-43592D01*
Y-45342D01*
X160475Y-47092D01*
X161567Y-48842D01*
X162877Y-50008D01*
X164405Y-50300D01*
X165933Y-49717D01*
X167462Y-47967D01*
G01X178193Y-50300D02*
Y-38634D01*
G01Y-40967D02*
X179285Y-39800D01*
X180377Y-38925D01*
X181905Y-38634D01*
X182996Y-38925D01*
X184307Y-39800D01*
G01X216250Y-38634D02*
Y-50300D01*
G01Y-33967D02*
X215813Y-33675D01*
Y-33092D01*
X216250Y-32800D01*
X216687Y-33092D01*
Y-33675D01*
X216250Y-33967D01*
G01X230475Y-48259D02*
X231567Y-49425D01*
X233095Y-50300D01*
X234405D01*
X235715Y-49717D01*
X236588Y-48842D01*
X237025Y-47676D01*
X236807Y-45925D01*
X235933Y-45050D01*
X232003Y-43300D01*
X231130Y-41258D01*
X231567Y-39800D01*
X232440Y-38925D01*
X233750Y-38634D01*
X235060Y-38925D01*
X236370Y-39800D01*
G01X265256Y-54675D02*
X266785Y-55842D01*
X268095Y-56133D01*
X269842Y-55550D01*
X271152Y-54092D01*
X271807Y-51466D01*
Y-38634D01*
G01Y-33967D02*
X271370Y-33675D01*
Y-33092D01*
X271807Y-32800D01*
X272243Y-33092D01*
Y-33675D01*
X271807Y-33967D01*
G01X282538Y-38634D02*
Y-46800D01*
X283412Y-48842D01*
X284722Y-50008D01*
X286250Y-50300D01*
X287778Y-50008D01*
X289088Y-48842D01*
X289962Y-46800D01*
G01Y-50300D02*
Y-38634D01*
G01X300475Y-48259D02*
X301567Y-49425D01*
X303095Y-50300D01*
X304405D01*
X305715Y-49717D01*
X306588Y-48842D01*
X307025Y-47676D01*
X306807Y-45925D01*
X305933Y-45050D01*
X302003Y-43300D01*
X301130Y-41258D01*
X301567Y-39800D01*
X302440Y-38925D01*
X303750Y-38634D01*
X305060Y-38925D01*
X306370Y-39800D01*
G01X321250Y-32800D02*
Y-50300D01*
G01X318193Y-38634D02*
X324307D01*
G01X354940Y-50300D02*
Y-35425D01*
X355377Y-33967D01*
X356250Y-33092D01*
X357560Y-32800D01*
X358870Y-33383D01*
X359525Y-34842D01*
G01X356905Y-39800D02*
X352538D01*
G01X373750Y-50300D02*
X372440Y-50008D01*
X371130Y-48842D01*
X370256Y-46800D01*
X369820Y-44467D01*
X370256Y-42133D01*
X371130Y-40092D01*
X372440Y-38925D01*
X373750Y-38634D01*
X375060Y-38925D01*
X376370Y-40092D01*
X377243Y-42133D01*
X377462Y-44467D01*
X377243Y-46800D01*
X376370Y-48842D01*
X375060Y-50008D01*
X373750Y-50300D01*
G01X388193D02*
Y-38634D01*
G01Y-40967D02*
X389285Y-39800D01*
X390377Y-38925D01*
X391905Y-38634D01*
X392996Y-38925D01*
X394307Y-39800D01*
G01X421665Y-55550D02*
X422975Y-56133D01*
X424722Y-55550D01*
X425813Y-54384D01*
X426687Y-52925D01*
X427996Y-48259D01*
X430835Y-38634D01*
G01X423848D02*
X427996Y-48259D01*
G01X443750Y-50300D02*
X442440Y-50008D01*
X441130Y-48842D01*
X440256Y-46800D01*
X439820Y-44467D01*
X440256Y-42133D01*
X441130Y-40092D01*
X442440Y-38925D01*
X443750Y-38634D01*
X445060Y-38925D01*
X446370Y-40092D01*
X447243Y-42133D01*
X447462Y-44467D01*
X447243Y-46800D01*
X446370Y-48842D01*
X445060Y-50008D01*
X443750Y-50300D01*
G01X457538Y-38634D02*
Y-46800D01*
X458412Y-48842D01*
X459722Y-50008D01*
X461250Y-50300D01*
X462778Y-50008D01*
X464088Y-48842D01*
X464962Y-46800D01*
G01Y-50300D02*
Y-38634D01*
G01X475693Y-50300D02*
Y-38634D01*
G01Y-40967D02*
X476785Y-39800D01*
X477877Y-38925D01*
X479405Y-38634D01*
X480496Y-38925D01*
X481807Y-39800D01*
G01X510693Y-50300D02*
Y-38634D01*
G01Y-40967D02*
X511785Y-39800D01*
X512877Y-38925D01*
X514405Y-38634D01*
X515496Y-38925D01*
X516807Y-39800D01*
G01X527975Y-42425D02*
X534962D01*
X534307Y-40383D01*
X533215Y-39217D01*
X531687Y-38634D01*
X530158Y-38925D01*
X528848Y-39800D01*
X527975Y-41842D01*
X527538Y-43592D01*
Y-45342D01*
X527975Y-47092D01*
X529067Y-48842D01*
X530377Y-50008D01*
X531905Y-50300D01*
X533433Y-49717D01*
X534962Y-47967D01*
G01X547440Y-50300D02*
Y-35425D01*
X547877Y-33967D01*
X548750Y-33092D01*
X550060Y-32800D01*
X551370Y-33383D01*
X552025Y-34842D01*
G01X549405Y-39800D02*
X545038D01*
G01X562975Y-42425D02*
X569962D01*
X569307Y-40383D01*
X568215Y-39217D01*
X566687Y-38634D01*
X565158Y-38925D01*
X563848Y-39800D01*
X562975Y-41842D01*
X562538Y-43592D01*
Y-45342D01*
X562975Y-47092D01*
X564067Y-48842D01*
X565377Y-50008D01*
X566905Y-50300D01*
X568433Y-49717D01*
X569962Y-47967D01*
G01X580693Y-50300D02*
Y-38634D01*
G01Y-40967D02*
X581785Y-39800D01*
X582877Y-38925D01*
X584405Y-38634D01*
X585496Y-38925D01*
X586807Y-39800D01*
G01X597975Y-42425D02*
X604962D01*
X604307Y-40383D01*
X603215Y-39217D01*
X601687Y-38634D01*
X600158Y-38925D01*
X598848Y-39800D01*
X597975Y-41842D01*
X597538Y-43592D01*
Y-45342D01*
X597975Y-47092D01*
X599067Y-48842D01*
X600377Y-50008D01*
X601905Y-50300D01*
X603433Y-49717D01*
X604962Y-47967D01*
G01X615038Y-50300D02*
Y-38634D01*
G01Y-41550D02*
X615912Y-40092D01*
X617222Y-38925D01*
X618968Y-38634D01*
X620496Y-38925D01*
X621807Y-40092D01*
X622462Y-42133D01*
Y-50300D01*
G01X639743Y-40092D02*
X638215Y-38925D01*
X636905Y-38634D01*
X635158Y-39217D01*
X633848Y-40383D01*
X632975Y-42425D01*
X632756Y-44467D01*
X632975Y-46509D01*
X633848Y-48259D01*
X635158Y-49717D01*
X636905Y-50300D01*
X638433Y-49717D01*
X639743Y-48550D01*
G01X650475Y-42425D02*
X657462D01*
X656807Y-40383D01*
X655715Y-39217D01*
X654187Y-38634D01*
X652658Y-38925D01*
X651348Y-39800D01*
X650475Y-41842D01*
X650038Y-43592D01*
Y-45342D01*
X650475Y-47092D01*
X651567Y-48842D01*
X652877Y-50008D01*
X654405Y-50300D01*
X655933Y-49717D01*
X657462Y-47967D01*
G01X688750Y-32800D02*
Y-50300D01*
G01X685693Y-38634D02*
X691807D01*
G01X706250Y-50300D02*
X704940Y-50008D01*
X703630Y-48842D01*
X702756Y-46800D01*
X702320Y-44467D01*
X702756Y-42133D01*
X703630Y-40092D01*
X704940Y-38925D01*
X706250Y-38634D01*
X707560Y-38925D01*
X708870Y-40092D01*
X709743Y-42133D01*
X709962Y-44467D01*
X709743Y-46800D01*
X708870Y-48842D01*
X707560Y-50008D01*
X706250Y-50300D01*
G01X739940D02*
Y-35425D01*
X740377Y-33967D01*
X741250Y-33092D01*
X742560Y-32800D01*
X743870Y-33383D01*
X744525Y-34842D01*
G01X741905Y-39800D02*
X737538D01*
G01X758750Y-38634D02*
Y-50300D01*
G01Y-33967D02*
X758313Y-33675D01*
Y-33092D01*
X758750Y-32800D01*
X759187Y-33092D01*
Y-33675D01*
X758750Y-33967D01*
G01X772538Y-50300D02*
Y-38634D01*
G01Y-41550D02*
X773412Y-40092D01*
X774722Y-38925D01*
X776468Y-38634D01*
X777996Y-38925D01*
X779307Y-40092D01*
X779962Y-42133D01*
Y-50300D01*
G01X797680Y-32800D02*
Y-50300D01*
G01Y-47676D02*
X796807Y-49134D01*
X795496Y-50008D01*
X793968Y-50300D01*
X792222Y-49717D01*
X790912Y-48259D01*
X790038Y-46509D01*
X789820Y-44467D01*
X790038Y-42425D01*
X790912Y-40675D01*
X792222Y-39217D01*
X793968Y-38634D01*
X795496Y-38925D01*
X796588Y-39509D01*
X797680Y-40675D01*
G01X828750Y-32800D02*
Y-50300D01*
G01X825693Y-38634D02*
X831807D01*
G01X842538Y-50300D02*
Y-32800D01*
G01Y-41258D02*
X843630Y-39800D01*
X844722Y-38925D01*
X846468Y-38634D01*
X847778Y-38925D01*
X849307Y-40092D01*
X849962Y-41842D01*
Y-50300D01*
G01X860475Y-42425D02*
X867462D01*
X866807Y-40383D01*
X865715Y-39217D01*
X864187Y-38634D01*
X862658Y-38925D01*
X861348Y-39800D01*
X860475Y-41842D01*
X860038Y-43592D01*
Y-45342D01*
X860475Y-47092D01*
X861567Y-48842D01*
X862877Y-50008D01*
X864405Y-50300D01*
X865933Y-49717D01*
X867462Y-47967D01*
G01X893947Y-50300D02*
Y-32800D01*
X898313D01*
X900060Y-33675D01*
X901370Y-34842D01*
X902462Y-36591D01*
X903335Y-38634D01*
X903553Y-41550D01*
X903335Y-44467D01*
X902462Y-46509D01*
X901370Y-48259D01*
X900060Y-49425D01*
X898313Y-50300D01*
X893947D01*
G01X911883D02*
Y-32800D01*
X917123D01*
X918870Y-33675D01*
X920180Y-35717D01*
X920617Y-38050D01*
X920180Y-40383D01*
X919088Y-42133D01*
X917123Y-43009D01*
X911883D01*
G01X951250Y-38634D02*
Y-50300D01*
G01Y-33967D02*
X950813Y-33675D01*
Y-33092D01*
X951250Y-32800D01*
X951687Y-33092D01*
Y-33675D01*
X951250Y-33967D01*
G01X962200Y-50300D02*
Y-38634D01*
G01Y-41842D02*
X962855Y-40383D01*
X963947Y-39217D01*
X965475Y-38634D01*
X967003Y-39217D01*
X968095Y-40383D01*
X968750Y-41842D01*
Y-50300D01*
G01Y-41842D02*
X969405Y-40383D01*
X970496Y-39217D01*
X972025Y-38634D01*
X973553Y-39217D01*
X974645Y-40383D01*
X975300Y-42133D01*
Y-50300D01*
G01X982320Y-56133D02*
Y-38634D01*
G01Y-41258D02*
X983412Y-39800D01*
X984503Y-38925D01*
X986250Y-38634D01*
X987778Y-38925D01*
X989307Y-40383D01*
X989962Y-42425D01*
X990180Y-44467D01*
X989962Y-46509D01*
X989307Y-48550D01*
X987996Y-49717D01*
X986250Y-50300D01*
X984722Y-50008D01*
X983193Y-49134D01*
X982320Y-47967D01*
G01X1000475Y-42425D02*
X1007462D01*
X1006807Y-40383D01*
X1005715Y-39217D01*
X1004187Y-38634D01*
X1002658Y-38925D01*
X1001348Y-39800D01*
X1000475Y-41842D01*
X1000038Y-43592D01*
Y-45342D01*
X1000475Y-47092D01*
X1001567Y-48842D01*
X1002877Y-50008D01*
X1004405Y-50300D01*
X1005933Y-49717D01*
X1007462Y-47967D01*
G01X1025180Y-32800D02*
Y-50300D01*
G01Y-47676D02*
X1024307Y-49134D01*
X1022996Y-50008D01*
X1021468Y-50300D01*
X1019722Y-49717D01*
X1018412Y-48259D01*
X1017538Y-46509D01*
X1017320Y-44467D01*
X1017538Y-42425D01*
X1018412Y-40675D01*
X1019722Y-39217D01*
X1021468Y-38634D01*
X1022996Y-38925D01*
X1024088Y-39509D01*
X1025180Y-40675D01*
G01X1042680Y-50300D02*
Y-38634D01*
G01Y-40675D02*
X1041807Y-39509D01*
X1040496Y-38925D01*
X1038968Y-38634D01*
X1037440Y-39217D01*
X1036130Y-40383D01*
X1035256Y-42133D01*
X1034820Y-44467D01*
X1035256Y-46800D01*
X1036130Y-48550D01*
X1037440Y-49717D01*
X1038968Y-50300D01*
X1040496Y-50008D01*
X1041807Y-49134D01*
X1042680Y-47967D01*
G01X1052538Y-50300D02*
Y-38634D01*
G01Y-41550D02*
X1053412Y-40092D01*
X1054722Y-38925D01*
X1056468Y-38634D01*
X1057996Y-38925D01*
X1059307Y-40092D01*
X1059962Y-42133D01*
Y-50300D01*
G01X1077243Y-40092D02*
X1075715Y-38925D01*
X1074405Y-38634D01*
X1072658Y-39217D01*
X1071348Y-40383D01*
X1070475Y-42425D01*
X1070256Y-44467D01*
X1070475Y-46509D01*
X1071348Y-48259D01*
X1072658Y-49717D01*
X1074405Y-50300D01*
X1075933Y-49717D01*
X1077243Y-48550D01*
G01X1087975Y-42425D02*
X1094962D01*
X1094307Y-40383D01*
X1093215Y-39217D01*
X1091687Y-38634D01*
X1090158Y-38925D01*
X1088848Y-39800D01*
X1087975Y-41842D01*
X1087538Y-43592D01*
Y-45342D01*
X1087975Y-47092D01*
X1089067Y-48842D01*
X1090377Y-50008D01*
X1091905Y-50300D01*
X1093433Y-49717D01*
X1094962Y-47967D01*
G01X1126250Y-32800D02*
Y-50300D01*
G01X1123193Y-38634D02*
X1129307D01*
G01X1140693Y-50300D02*
Y-38634D01*
G01Y-40967D02*
X1141785Y-39800D01*
X1142877Y-38925D01*
X1144405Y-38634D01*
X1145496Y-38925D01*
X1146807Y-39800D01*
G01X1165180Y-50300D02*
Y-38634D01*
G01Y-40675D02*
X1164307Y-39509D01*
X1162996Y-38925D01*
X1161468Y-38634D01*
X1159940Y-39217D01*
X1158630Y-40383D01*
X1157756Y-42133D01*
X1157320Y-44467D01*
X1157756Y-46800D01*
X1158630Y-48550D01*
X1159940Y-49717D01*
X1161468Y-50300D01*
X1162996Y-50008D01*
X1164307Y-49134D01*
X1165180Y-47967D01*
G01X1182243Y-40092D02*
X1180715Y-38925D01*
X1179405Y-38634D01*
X1177658Y-39217D01*
X1176348Y-40383D01*
X1175475Y-42425D01*
X1175256Y-44467D01*
X1175475Y-46509D01*
X1176348Y-48259D01*
X1177658Y-49717D01*
X1179405Y-50300D01*
X1180933Y-49717D01*
X1182243Y-48550D01*
G01X1192975Y-42425D02*
X1199962D01*
X1199307Y-40383D01*
X1198215Y-39217D01*
X1196687Y-38634D01*
X1195158Y-38925D01*
X1193848Y-39800D01*
X1192975Y-41842D01*
X1192538Y-43592D01*
Y-45342D01*
X1192975Y-47092D01*
X1194067Y-48842D01*
X1195377Y-50008D01*
X1196905Y-50300D01*
X1198433Y-49717D01*
X1199962Y-47967D01*
G01X1210475Y-48259D02*
X1211567Y-49425D01*
X1213095Y-50300D01*
X1214405D01*
X1215715Y-49717D01*
X1216588Y-48842D01*
X1217025Y-47676D01*
X1216807Y-45925D01*
X1215933Y-45050D01*
X1212003Y-43300D01*
X1211130Y-41258D01*
X1211567Y-39800D01*
X1212440Y-38925D01*
X1213750Y-38634D01*
X1215060Y-38925D01*
X1216370Y-39800D01*
G01X1248750Y-38634D02*
Y-50300D01*
G01Y-33967D02*
X1248313Y-33675D01*
Y-33092D01*
X1248750Y-32800D01*
X1249187Y-33092D01*
Y-33675D01*
X1248750Y-33967D01*
G01X1262538Y-50300D02*
Y-38634D01*
G01Y-41550D02*
X1263412Y-40092D01*
X1264722Y-38925D01*
X1266468Y-38634D01*
X1267996Y-38925D01*
X1269307Y-40092D01*
X1269962Y-42133D01*
Y-50300D01*
G01X1301250D02*
Y-32800D01*
G01X1322680Y-50300D02*
Y-38634D01*
G01Y-40675D02*
X1321807Y-39509D01*
X1320496Y-38925D01*
X1318968Y-38634D01*
X1317440Y-39217D01*
X1316130Y-40383D01*
X1315256Y-42133D01*
X1314820Y-44467D01*
X1315256Y-46800D01*
X1316130Y-48550D01*
X1317440Y-49717D01*
X1318968Y-50300D01*
X1320496Y-50008D01*
X1321807Y-49134D01*
X1322680Y-47967D01*
G01X1331665Y-55550D02*
X1332975Y-56133D01*
X1334722Y-55550D01*
X1335813Y-54384D01*
X1336687Y-52925D01*
X1337996Y-48259D01*
X1340835Y-38634D01*
G01X1333848D02*
X1337996Y-48259D01*
G01X1350475Y-42425D02*
X1357462D01*
X1356807Y-40383D01*
X1355715Y-39217D01*
X1354187Y-38634D01*
X1352658Y-38925D01*
X1351348Y-39800D01*
X1350475Y-41842D01*
X1350038Y-43592D01*
Y-45342D01*
X1350475Y-47092D01*
X1351567Y-48842D01*
X1352877Y-50008D01*
X1354405Y-50300D01*
X1355933Y-49717D01*
X1357462Y-47967D01*
G01X1368193Y-50300D02*
Y-38634D01*
G01Y-40967D02*
X1369285Y-39800D01*
X1370377Y-38925D01*
X1371905Y-38634D01*
X1372996Y-38925D01*
X1374307Y-39800D01*
G01X1401883Y-32800D02*
Y-50300D01*
X1410617D01*
G01X1419602Y-43009D02*
X1421130Y-40967D01*
X1422440Y-39800D01*
X1424187Y-39217D01*
X1425715Y-39800D01*
X1426807Y-40967D01*
X1427680Y-42717D01*
X1427898Y-44758D01*
X1427680Y-46509D01*
X1426807Y-48259D01*
X1425496Y-49717D01*
X1423968Y-50300D01*
X1422222Y-49717D01*
X1420693Y-47967D01*
X1419820Y-45342D01*
X1419602Y-42425D01*
X1420038Y-38634D01*
X1420693Y-36591D01*
X1421785Y-34550D01*
X1423313Y-33092D01*
X1424842Y-32800D01*
X1426370Y-33383D01*
X1427462Y-34842D01*
G01X1441250Y-50883D02*
X1440813Y-50592D01*
Y-50008D01*
X1441250Y-49717D01*
X1441687Y-50008D01*
Y-50592D01*
X1441250Y-50883D01*
G01X999127Y722030D02*
X1004367D01*
G01X1001747D02*
Y704530D01*
G01X999127D02*
X1004367D01*
G01X1013570D02*
Y722030D01*
X1019247Y707447D01*
X1024924Y722030D01*
Y704530D01*
G01X1032380D02*
Y722030D01*
X1037620D01*
X1039367Y721155D01*
X1040677Y719113D01*
X1041114Y716780D01*
X1040677Y714447D01*
X1039585Y712697D01*
X1037620Y711821D01*
X1032380D01*
G01X1053155Y698697D02*
X1050972Y701613D01*
X1049880Y704530D01*
Y716196D01*
X1050972Y719113D01*
X1053155Y722030D01*
G01X1071747Y704530D02*
X1070000Y704822D01*
X1068472Y705988D01*
X1067162Y707738D01*
X1066288Y709780D01*
X1065852Y712113D01*
Y714447D01*
X1066288Y716780D01*
X1067162Y718822D01*
X1068472Y720571D01*
X1070000Y721738D01*
X1071747Y722030D01*
X1073493Y721738D01*
X1075022Y720571D01*
X1076332Y718822D01*
X1077206Y716780D01*
X1077642Y714447D01*
Y712113D01*
X1077206Y709780D01*
X1076332Y707738D01*
X1075022Y705988D01*
X1073493Y704822D01*
X1071747Y704530D01*
G01X1085535D02*
Y722030D01*
G01Y713572D02*
X1086627Y715030D01*
X1087719Y715905D01*
X1089465Y716196D01*
X1090775Y715905D01*
X1092304Y714738D01*
X1092959Y712988D01*
Y704530D01*
G01X1100197D02*
Y716196D01*
G01Y712988D02*
X1100852Y714447D01*
X1101944Y715613D01*
X1103472Y716196D01*
X1105000Y715613D01*
X1106092Y714447D01*
X1106747Y712988D01*
Y704530D01*
G01Y712988D02*
X1107402Y714447D01*
X1108493Y715613D01*
X1110022Y716196D01*
X1111550Y715613D01*
X1112642Y714447D01*
X1113297Y712697D01*
Y704530D01*
G01X1125339Y698697D02*
X1127522Y701613D01*
X1128614Y704530D01*
Y716196D01*
X1127522Y719113D01*
X1125339Y722030D01*
G01X977244Y739180D02*
Y756680D01*
X981610D01*
X983357Y755805D01*
X984667Y754638D01*
X985759Y752889D01*
X986632Y750846D01*
X986850Y747930D01*
X986632Y745013D01*
X985759Y742971D01*
X984667Y741221D01*
X983357Y740055D01*
X981610Y739180D01*
X977244D01*
G01X995180D02*
Y756680D01*
X1000420D01*
X1002167Y755805D01*
X1003477Y753763D01*
X1003914Y751430D01*
X1003477Y749097D01*
X1002385Y747347D01*
X1000420Y746471D01*
X995180D01*
G01X1031927Y756680D02*
X1037167D01*
G01X1034547D02*
Y739180D01*
G01X1031927D02*
X1037167D01*
G01X1046370D02*
Y756680D01*
X1052047Y742097D01*
X1057724Y756680D01*
Y739180D01*
G01X1065180D02*
Y756680D01*
X1070420D01*
X1072167Y755805D01*
X1073477Y753763D01*
X1073914Y751430D01*
X1073477Y749097D01*
X1072385Y747347D01*
X1070420Y746471D01*
X1065180D01*
G01X1091414Y739180D02*
X1082680D01*
Y756680D01*
X1091414D01*
G01X1087920Y748222D02*
X1082680D01*
G01X1099744Y739180D02*
Y756680D01*
X1104110D01*
X1105857Y755805D01*
X1107167Y754638D01*
X1108259Y752889D01*
X1109132Y750846D01*
X1109350Y747930D01*
X1109132Y745013D01*
X1108259Y742971D01*
X1107167Y741221D01*
X1105857Y740055D01*
X1104110Y739180D01*
X1099744D01*
G01X1116588D02*
X1122047Y756680D01*
X1127506Y739180D01*
G01X1125540Y745305D02*
X1118553D01*
G01X1134525Y739180D02*
Y756680D01*
X1144569Y739180D01*
Y756680D01*
G01X1161850Y755221D02*
X1160540Y756097D01*
X1159012Y756680D01*
X1157265D01*
X1155300Y755805D01*
X1153772Y754347D01*
X1152680Y752596D01*
X1151807Y749680D01*
X1151588Y747055D01*
X1152025Y744430D01*
X1152680Y742680D01*
X1153990Y740930D01*
X1155519Y739763D01*
X1157047Y739180D01*
X1158575D01*
X1160104Y739763D01*
X1161414Y740638D01*
X1162506Y741804D01*
G01X1178914Y739180D02*
X1170180D01*
Y756680D01*
X1178914D01*
G01X1175420Y748222D02*
X1170180D01*
G01X1209547Y756680D02*
Y739180D01*
G01X1204525Y756680D02*
X1214569D01*
G01X1221588Y739180D02*
X1227047Y756680D01*
X1232506Y739180D01*
G01X1230540Y745305D02*
X1223553D01*
G01X1246293Y748513D02*
X1247167Y749388D01*
X1247822Y750846D01*
X1248259Y752889D01*
X1247822Y754638D01*
X1246949Y755805D01*
X1245420Y756680D01*
X1239525D01*
Y739180D01*
X1246730D01*
X1248259Y740346D01*
X1249132Y742097D01*
X1249569Y744138D01*
X1249132Y746180D01*
X1247822Y747930D01*
X1246293Y748513D01*
X1239525D01*
G01X1257680Y756680D02*
Y739180D01*
X1266414D01*
G01X1283914D02*
X1275180D01*
Y756680D01*
X1283914D01*
G01X1280420Y748222D02*
X1275180D01*
G01X1297047Y738597D02*
X1296610Y738888D01*
Y739472D01*
X1297047Y739763D01*
X1297484Y739472D01*
Y738888D01*
X1297047Y738597D01*
G01Y746471D02*
X1296610Y746763D01*
Y747347D01*
X1297047Y747638D01*
X1297484Y747347D01*
Y746763D01*
X1297047Y746471D01*
G01X1327680Y756680D02*
Y739180D01*
X1336414D01*
G01X1345399Y746471D02*
X1346927Y748513D01*
X1348237Y749680D01*
X1349984Y750263D01*
X1351512Y749680D01*
X1352604Y748513D01*
X1353477Y746763D01*
X1353695Y744722D01*
X1353477Y742971D01*
X1352604Y741221D01*
X1351293Y739763D01*
X1349765Y739180D01*
X1348019Y739763D01*
X1346490Y741513D01*
X1345617Y744138D01*
X1345399Y747055D01*
X1345835Y750846D01*
X1346490Y752889D01*
X1347582Y754930D01*
X1349110Y756388D01*
X1350639Y756680D01*
X1352167Y756097D01*
X1353259Y754638D01*
G01X1027997Y635230D02*
Y652730D01*
X1025377Y649230D01*
G01Y635230D02*
X1030617D01*
G01X1045497Y652730D02*
X1043750Y652147D01*
X1042440Y650688D01*
X1041567Y648939D01*
X1040912Y646605D01*
X1040694Y643980D01*
X1040912Y641355D01*
X1041567Y639021D01*
X1042440Y637271D01*
X1043750Y635813D01*
X1045497Y635230D01*
X1047243Y635813D01*
X1048554Y637271D01*
X1049427Y639021D01*
X1050082Y641355D01*
X1050300Y643980D01*
X1050082Y646605D01*
X1049427Y648939D01*
X1048554Y650688D01*
X1047243Y652147D01*
X1045497Y652730D01*
G01X1062997D02*
X1061250Y652147D01*
X1059940Y650688D01*
X1059067Y648939D01*
X1058412Y646605D01*
X1058194Y643980D01*
X1058412Y641355D01*
X1059067Y639021D01*
X1059940Y637271D01*
X1061250Y635813D01*
X1062997Y635230D01*
X1064743Y635813D01*
X1066054Y637271D01*
X1066927Y639021D01*
X1067582Y641355D01*
X1067800Y643980D01*
X1067582Y646605D01*
X1066927Y648939D01*
X1066054Y650688D01*
X1064743Y652147D01*
X1062997Y652730D01*
G01X1080497Y634647D02*
X1080060Y634938D01*
Y635522D01*
X1080497Y635813D01*
X1080934Y635522D01*
Y634938D01*
X1080497Y634647D01*
G01X1097997Y652730D02*
X1096250Y652147D01*
X1094940Y650688D01*
X1094067Y648939D01*
X1093412Y646605D01*
X1093194Y643980D01*
X1093412Y641355D01*
X1094067Y639021D01*
X1094940Y637271D01*
X1096250Y635813D01*
X1097997Y635230D01*
X1099743Y635813D01*
X1101054Y637271D01*
X1101927Y639021D01*
X1102582Y641355D01*
X1102800Y643980D01*
X1102582Y646605D01*
X1101927Y648939D01*
X1101054Y650688D01*
X1099743Y652147D01*
X1097997Y652730D01*
G01X1036747Y669880D02*
X1038275Y670172D01*
X1040022Y671046D01*
X1041114Y672504D01*
X1041550Y674547D01*
X1041114Y676588D01*
X1039804Y678338D01*
X1037839Y679213D01*
X1035655D01*
X1034345Y679797D01*
X1033253Y681255D01*
X1032817Y683296D01*
X1033472Y685338D01*
X1035000Y686797D01*
X1036747Y687380D01*
X1038493Y686797D01*
X1040022Y685338D01*
X1040677Y683296D01*
X1040240Y681255D01*
X1039149Y679797D01*
X1037839Y679213D01*
X1035655D01*
X1033690Y678338D01*
X1032380Y676588D01*
X1031944Y674547D01*
X1032380Y672504D01*
X1033472Y671046D01*
X1035219Y670172D01*
X1036747Y669880D01*
G01X1049444Y672504D02*
X1050753Y671046D01*
X1052282Y670172D01*
X1054247Y669880D01*
X1056212Y670463D01*
X1057740Y671630D01*
X1058832Y673671D01*
X1059050Y676005D01*
X1058614Y678338D01*
X1057522Y679797D01*
X1055993Y680963D01*
X1054465Y681255D01*
X1052937Y680963D01*
X1050972Y679797D01*
X1051627Y687380D01*
X1057522D01*
G01X1071747Y669297D02*
X1071310Y669588D01*
Y670172D01*
X1071747Y670463D01*
X1072184Y670172D01*
Y669588D01*
X1071747Y669297D01*
G01X1089247Y687380D02*
X1087500Y686797D01*
X1086190Y685338D01*
X1085317Y683589D01*
X1084662Y681255D01*
X1084444Y678630D01*
X1084662Y676005D01*
X1085317Y673671D01*
X1086190Y671921D01*
X1087500Y670463D01*
X1089247Y669880D01*
X1090993Y670463D01*
X1092304Y671921D01*
X1093177Y673671D01*
X1093832Y676005D01*
X1094050Y678630D01*
X1093832Y681255D01*
X1093177Y683589D01*
X1092304Y685338D01*
X1090993Y686797D01*
X1089247Y687380D01*
G01X1249367Y635230D02*
Y652730D01*
X1241288Y640188D01*
X1252206D01*
G01X1264247Y634647D02*
X1263810Y634938D01*
Y635522D01*
X1264247Y635813D01*
X1264684Y635522D01*
Y634938D01*
X1264247Y634647D01*
G01X1281747Y652730D02*
X1280000Y652147D01*
X1278690Y650688D01*
X1277817Y648939D01*
X1277162Y646605D01*
X1276944Y643980D01*
X1277162Y641355D01*
X1277817Y639021D01*
X1278690Y637271D01*
X1280000Y635813D01*
X1281747Y635230D01*
X1283493Y635813D01*
X1284804Y637271D01*
X1285677Y639021D01*
X1286332Y641355D01*
X1286550Y643980D01*
X1286332Y646605D01*
X1285677Y648939D01*
X1284804Y650688D01*
X1283493Y652147D01*
X1281747Y652730D01*
G01X1295317Y634647D02*
X1303177Y652730D01*
G01X1316747Y635230D02*
X1318275Y635522D01*
X1320022Y636396D01*
X1321114Y637854D01*
X1321550Y639897D01*
X1321114Y641938D01*
X1319804Y643688D01*
X1317839Y644563D01*
X1315655D01*
X1314345Y645147D01*
X1313253Y646605D01*
X1312817Y648646D01*
X1313472Y650688D01*
X1315000Y652147D01*
X1316747Y652730D01*
X1318493Y652147D01*
X1320022Y650688D01*
X1320677Y648646D01*
X1320240Y646605D01*
X1319149Y645147D01*
X1317839Y644563D01*
X1315655D01*
X1313690Y643688D01*
X1312380Y641938D01*
X1311944Y639897D01*
X1312380Y637854D01*
X1313472Y636396D01*
X1315219Y635522D01*
X1316747Y635230D01*
G01X1334247Y634647D02*
X1333810Y634938D01*
Y635522D01*
X1334247Y635813D01*
X1334684Y635522D01*
Y634938D01*
X1334247Y634647D01*
G01X1351747Y652730D02*
X1350000Y652147D01*
X1348690Y650688D01*
X1347817Y648939D01*
X1347162Y646605D01*
X1346944Y643980D01*
X1347162Y641355D01*
X1347817Y639021D01*
X1348690Y637271D01*
X1350000Y635813D01*
X1351747Y635230D01*
X1353493Y635813D01*
X1354804Y637271D01*
X1355677Y639021D01*
X1356332Y641355D01*
X1356550Y643980D01*
X1356332Y646605D01*
X1355677Y648939D01*
X1354804Y650688D01*
X1353493Y652147D01*
X1351747Y652730D01*
G01X1205197Y722030D02*
X1208253Y704530D01*
X1211747Y722030D01*
X1215240Y704530D01*
X1218297Y722030D01*
G01X1226627D02*
X1231867D01*
G01X1229247D02*
Y704530D01*
G01X1226627D02*
X1231867D01*
G01X1241944D02*
Y722030D01*
X1246310D01*
X1248057Y721155D01*
X1249367Y719988D01*
X1250459Y718239D01*
X1251332Y716196D01*
X1251550Y713280D01*
X1251332Y710363D01*
X1250459Y708321D01*
X1249367Y706571D01*
X1248057Y705405D01*
X1246310Y704530D01*
X1241944D01*
G01X1264247Y722030D02*
Y704530D01*
G01X1259225Y722030D02*
X1269269D01*
G01X1277162Y704530D02*
Y722030D01*
G01X1286332D02*
Y704530D01*
G01Y713280D02*
X1277162D01*
G01X1298155Y698697D02*
X1295972Y701613D01*
X1294880Y704530D01*
Y716196D01*
X1295972Y719113D01*
X1298155Y722030D01*
G01X1310197Y704530D02*
Y716196D01*
G01Y712988D02*
X1310852Y714447D01*
X1311944Y715613D01*
X1313472Y716196D01*
X1315000Y715613D01*
X1316092Y714447D01*
X1316747Y712988D01*
Y704530D01*
G01Y712988D02*
X1317402Y714447D01*
X1318493Y715613D01*
X1320022Y716196D01*
X1321550Y715613D01*
X1322642Y714447D01*
X1323297Y712697D01*
Y704530D01*
G01X1334247Y716196D02*
Y704530D01*
G01Y720863D02*
X1333810Y721155D01*
Y721738D01*
X1334247Y722030D01*
X1334684Y721738D01*
Y721155D01*
X1334247Y720863D01*
G01X1351747Y704530D02*
Y722030D01*
G01X1365972Y706571D02*
X1367064Y705405D01*
X1368592Y704530D01*
X1369902D01*
X1371212Y705113D01*
X1372085Y705988D01*
X1372522Y707154D01*
X1372304Y708905D01*
X1371430Y709780D01*
X1367500Y711530D01*
X1366627Y713572D01*
X1367064Y715030D01*
X1367937Y715905D01*
X1369247Y716196D01*
X1370557Y715905D01*
X1371867Y715030D01*
G01X1387839Y698697D02*
X1390022Y701613D01*
X1391114Y704530D01*
Y716196D01*
X1390022Y719113D01*
X1387839Y722030D01*
G01X1241944Y672504D02*
X1243253Y671046D01*
X1244782Y670172D01*
X1246747Y669880D01*
X1248712Y670463D01*
X1250240Y671630D01*
X1251332Y673671D01*
X1251550Y676005D01*
X1251114Y678338D01*
X1250022Y679797D01*
X1248493Y680963D01*
X1246965Y681255D01*
X1245437Y680963D01*
X1243472Y679797D01*
X1244127Y687380D01*
X1250022D01*
G01X1264247Y669297D02*
X1263810Y669588D01*
Y670172D01*
X1264247Y670463D01*
X1264684Y670172D01*
Y669588D01*
X1264247Y669297D01*
G01X1276944Y672504D02*
X1278253Y671046D01*
X1279782Y670172D01*
X1281747Y669880D01*
X1283712Y670463D01*
X1285240Y671630D01*
X1286332Y673671D01*
X1286550Y676005D01*
X1286114Y678338D01*
X1285022Y679797D01*
X1283493Y680963D01*
X1281965Y681255D01*
X1280437Y680963D01*
X1278472Y679797D01*
X1279127Y687380D01*
X1285022D01*
G01X1295317Y669297D02*
X1303177Y687380D01*
G01X1316310Y669880D02*
X1316747Y673671D01*
X1317402Y676880D01*
X1318275Y679797D01*
X1319367Y683005D01*
X1321114Y687380D01*
X1312380D01*
G01X1334247Y669297D02*
X1333810Y669588D01*
Y670172D01*
X1334247Y670463D01*
X1334684Y670172D01*
Y669588D01*
X1334247Y669297D01*
G01X1346944Y672504D02*
X1348253Y671046D01*
X1349782Y670172D01*
X1351747Y669880D01*
X1353712Y670463D01*
X1355240Y671630D01*
X1356332Y673671D01*
X1356550Y676005D01*
X1356114Y678338D01*
X1355022Y679797D01*
X1353493Y680963D01*
X1351965Y681255D01*
X1350437Y680963D01*
X1348472Y679797D01*
X1349127Y687380D01*
X1355022D01*
G01X1486944Y635230D02*
Y652730D01*
X1491310D01*
X1493057Y651855D01*
X1494367Y650688D01*
X1495459Y648939D01*
X1496332Y646896D01*
X1496550Y643980D01*
X1496332Y641063D01*
X1495459Y639021D01*
X1494367Y637271D01*
X1493057Y636105D01*
X1491310Y635230D01*
X1486944D01*
G01X1504880D02*
Y652730D01*
X1510120D01*
X1511867Y651855D01*
X1513177Y649813D01*
X1513614Y647480D01*
X1513177Y645147D01*
X1512085Y643397D01*
X1510120Y642521D01*
X1504880D01*
G01X1474247Y722030D02*
Y704530D01*
G01X1469225Y722030D02*
X1479269D01*
G01X1491747Y704530D02*
Y712405D01*
X1487380Y722030D01*
G01X1496114D02*
X1491747Y712405D01*
G01X1504880Y704530D02*
Y722030D01*
X1510120D01*
X1511867Y721155D01*
X1513177Y719113D01*
X1513614Y716780D01*
X1513177Y714447D01*
X1512085Y712697D01*
X1510120Y711821D01*
X1504880D01*
G01X1531114Y704530D02*
X1522380D01*
Y722030D01*
X1531114D01*
G01X1527620Y713572D02*
X1522380D01*
G01X1486944Y669880D02*
Y687380D01*
X1491310D01*
X1493057Y686505D01*
X1494367Y685338D01*
X1495459Y683589D01*
X1496332Y681546D01*
X1496550Y678630D01*
X1496332Y675713D01*
X1495459Y673671D01*
X1494367Y671921D01*
X1493057Y670755D01*
X1491310Y669880D01*
X1486944D01*
G01X1504880D02*
Y687380D01*
X1510120D01*
X1511867Y686505D01*
X1513177Y684463D01*
X1513614Y682130D01*
X1513177Y679797D01*
X1512085Y678047D01*
X1510120Y677171D01*
X1504880D01*
G01X1574880Y704530D02*
Y722030D01*
X1580339D01*
X1582085Y721155D01*
X1583177Y719988D01*
X1583614Y717655D01*
X1583177Y715321D01*
X1581867Y713863D01*
X1580339Y712988D01*
X1574880D01*
G01X1580339D02*
X1583614Y704530D01*
G01X1593472Y712405D02*
X1600459D01*
X1599804Y714447D01*
X1598712Y715613D01*
X1597184Y716196D01*
X1595655Y715905D01*
X1594345Y715030D01*
X1593472Y712988D01*
X1593035Y711238D01*
Y709488D01*
X1593472Y707738D01*
X1594564Y705988D01*
X1595874Y704822D01*
X1597402Y704530D01*
X1598930Y705113D01*
X1600459Y706863D01*
G01X1612937Y704530D02*
Y719405D01*
X1613374Y720863D01*
X1614247Y721738D01*
X1615557Y722030D01*
X1616867Y721447D01*
X1617522Y719988D01*
G01X1614902Y715030D02*
X1610535D01*
G01X1631747Y703947D02*
X1631310Y704238D01*
Y704822D01*
X1631747Y705113D01*
X1632184Y704822D01*
Y704238D01*
X1631747Y703947D01*
G01X1662380Y704530D02*
Y722030D01*
X1667620D01*
X1669367Y721155D01*
X1670677Y719113D01*
X1671114Y716780D01*
X1670677Y714447D01*
X1669585Y712697D01*
X1667620Y711821D01*
X1662380D01*
G01X1684247Y704530D02*
Y722030D01*
G01X1705677Y704530D02*
Y716196D01*
G01Y714155D02*
X1704804Y715321D01*
X1703493Y715905D01*
X1701965Y716196D01*
X1700437Y715613D01*
X1699127Y714447D01*
X1698253Y712697D01*
X1697817Y710363D01*
X1698253Y708030D01*
X1699127Y706280D01*
X1700437Y705113D01*
X1701965Y704530D01*
X1703493Y704822D01*
X1704804Y705696D01*
X1705677Y706863D01*
G01X1715535Y704530D02*
Y716196D01*
G01Y713280D02*
X1716409Y714738D01*
X1717719Y715905D01*
X1719465Y716196D01*
X1720993Y715905D01*
X1722304Y714738D01*
X1722959Y712697D01*
Y704530D01*
G01X1733472Y712405D02*
X1740459D01*
X1739804Y714447D01*
X1738712Y715613D01*
X1737184Y716196D01*
X1735655Y715905D01*
X1734345Y715030D01*
X1733472Y712988D01*
X1733035Y711238D01*
Y709488D01*
X1733472Y707738D01*
X1734564Y705988D01*
X1735874Y704822D01*
X1737402Y704530D01*
X1738930Y705113D01*
X1740459Y706863D01*
G01X1618630Y652730D02*
Y635230D01*
X1627364D01*
G01X1635694Y637854D02*
X1637003Y636396D01*
X1638532Y635522D01*
X1640497Y635230D01*
X1642462Y635813D01*
X1643990Y636980D01*
X1645082Y639021D01*
X1645300Y641355D01*
X1644864Y643688D01*
X1643772Y645147D01*
X1642243Y646313D01*
X1640715Y646605D01*
X1639187Y646313D01*
X1637222Y645147D01*
X1637877Y652730D01*
X1643772D01*
G01X1654067Y634647D02*
X1661927Y652730D01*
G01X1671130D02*
Y635230D01*
X1679864D01*
G01X1692560D02*
X1692997Y639021D01*
X1693652Y642230D01*
X1694525Y645147D01*
X1695617Y648355D01*
X1697364Y652730D01*
X1688630D01*
G01X1618630Y687380D02*
Y669880D01*
X1627364D01*
G01X1635694Y672504D02*
X1637003Y671046D01*
X1638532Y670172D01*
X1640497Y669880D01*
X1642462Y670463D01*
X1643990Y671630D01*
X1645082Y673671D01*
X1645300Y676005D01*
X1644864Y678338D01*
X1643772Y679797D01*
X1642243Y680963D01*
X1640715Y681255D01*
X1639187Y680963D01*
X1637222Y679797D01*
X1637877Y687380D01*
X1643772D01*
G01X1654067Y669297D02*
X1661927Y687380D01*
G01X1671130D02*
Y669880D01*
X1679864D01*
G01X1692560D02*
X1692997Y673671D01*
X1693652Y676880D01*
X1694525Y679797D01*
X1695617Y683005D01*
X1697364Y687380D01*
X1688630D01*
G01X1779744Y703947D02*
X1789350Y716780D01*
G01X1784547Y719113D02*
Y701613D01*
G01X1789350Y703947D02*
X1779744Y716780D01*
G01X1777997Y710363D02*
X1791097D01*
G01X1816709D02*
X1822385D01*
G01X1849744Y704530D02*
Y722030D01*
X1854110D01*
X1855857Y721155D01*
X1857167Y719988D01*
X1858259Y718239D01*
X1859132Y716196D01*
X1859350Y713280D01*
X1859132Y710363D01*
X1858259Y708321D01*
X1857167Y706571D01*
X1855857Y705405D01*
X1854110Y704530D01*
X1849744D01*
G01X1868772Y712405D02*
X1875759D01*
X1875104Y714447D01*
X1874012Y715613D01*
X1872484Y716196D01*
X1870955Y715905D01*
X1869645Y715030D01*
X1868772Y712988D01*
X1868335Y711238D01*
Y709488D01*
X1868772Y707738D01*
X1869864Y705988D01*
X1871174Y704822D01*
X1872702Y704530D01*
X1874230Y705113D01*
X1875759Y706863D01*
G01X1885835Y704530D02*
Y716196D01*
G01Y713280D02*
X1886709Y714738D01*
X1888019Y715905D01*
X1889765Y716196D01*
X1891293Y715905D01*
X1892604Y714738D01*
X1893259Y712697D01*
Y704530D01*
G01X1907047D02*
X1905737Y704822D01*
X1904427Y705988D01*
X1903553Y708030D01*
X1903117Y710363D01*
X1903553Y712697D01*
X1904427Y714738D01*
X1905737Y715905D01*
X1907047Y716196D01*
X1908357Y715905D01*
X1909667Y714738D01*
X1910540Y712697D01*
X1910759Y710363D01*
X1910540Y708030D01*
X1909667Y705988D01*
X1908357Y704822D01*
X1907047Y704530D01*
G01X1924547Y722030D02*
Y704530D01*
G01X1921490Y716196D02*
X1927604D01*
G01X1938772Y712405D02*
X1945759D01*
X1945104Y714447D01*
X1944012Y715613D01*
X1942484Y716196D01*
X1940955Y715905D01*
X1939645Y715030D01*
X1938772Y712988D01*
X1938335Y711238D01*
Y709488D01*
X1938772Y707738D01*
X1939864Y705988D01*
X1941174Y704822D01*
X1942702Y704530D01*
X1944230Y705113D01*
X1945759Y706863D01*
G01X1956272Y706571D02*
X1957364Y705405D01*
X1958892Y704530D01*
X1960202D01*
X1961512Y705113D01*
X1962385Y705988D01*
X1962822Y707154D01*
X1962604Y708905D01*
X1961730Y709780D01*
X1957800Y711530D01*
X1956927Y713572D01*
X1957364Y715030D01*
X1958237Y715905D01*
X1959547Y716196D01*
X1960857Y715905D01*
X1962167Y715030D01*
G01X1994547Y722030D02*
Y704530D01*
G01X1991490Y716196D02*
X1997604D01*
G01X2008335Y704530D02*
Y722030D01*
G01Y713572D02*
X2009427Y715030D01*
X2010519Y715905D01*
X2012265Y716196D01*
X2013575Y715905D01*
X2015104Y714738D01*
X2015759Y712988D01*
Y704530D01*
G01X2033477D02*
Y716196D01*
G01Y714155D02*
X2032604Y715321D01*
X2031293Y715905D01*
X2029765Y716196D01*
X2028237Y715613D01*
X2026927Y714447D01*
X2026053Y712697D01*
X2025617Y710363D01*
X2026053Y708030D01*
X2026927Y706280D01*
X2028237Y705113D01*
X2029765Y704530D01*
X2031293Y704822D01*
X2032604Y705696D01*
X2033477Y706863D01*
G01X2047047Y722030D02*
Y704530D01*
G01X2043990Y716196D02*
X2050104D01*
G01X2082047Y722030D02*
Y704530D01*
G01X2078990Y716196D02*
X2085104D01*
G01X2095835Y704530D02*
Y722030D01*
G01Y713572D02*
X2096927Y715030D01*
X2098019Y715905D01*
X2099765Y716196D01*
X2101075Y715905D01*
X2102604Y714738D01*
X2103259Y712988D01*
Y704530D01*
G01X2117047Y716196D02*
Y704530D01*
G01Y720863D02*
X2116610Y721155D01*
Y721738D01*
X2117047Y722030D01*
X2117484Y721738D01*
Y721155D01*
X2117047Y720863D01*
G01X2131272Y706571D02*
X2132364Y705405D01*
X2133892Y704530D01*
X2135202D01*
X2136512Y705113D01*
X2137385Y705988D01*
X2137822Y707154D01*
X2137604Y708905D01*
X2136730Y709780D01*
X2132800Y711530D01*
X2131927Y713572D01*
X2132364Y715030D01*
X2133237Y715905D01*
X2134547Y716196D01*
X2135857Y715905D01*
X2137167Y715030D01*
G01X2166927Y722030D02*
X2172167D01*
G01X2169547D02*
Y704530D01*
G01X2166927D02*
X2172167D01*
G01X2180497D02*
Y716196D01*
G01Y712988D02*
X2181152Y714447D01*
X2182244Y715613D01*
X2183772Y716196D01*
X2185300Y715613D01*
X2186392Y714447D01*
X2187047Y712988D01*
Y704530D01*
G01Y712988D02*
X2187702Y714447D01*
X2188793Y715613D01*
X2190322Y716196D01*
X2191850Y715613D01*
X2192942Y714447D01*
X2193597Y712697D01*
Y704530D01*
G01X2200617Y698697D02*
Y716196D01*
G01Y713572D02*
X2201709Y715030D01*
X2202800Y715905D01*
X2204547Y716196D01*
X2206075Y715905D01*
X2207604Y714447D01*
X2208259Y712405D01*
X2208477Y710363D01*
X2208259Y708321D01*
X2207604Y706280D01*
X2206293Y705113D01*
X2204547Y704530D01*
X2203019Y704822D01*
X2201490Y705696D01*
X2200617Y706863D01*
G01X2218772Y712405D02*
X2225759D01*
X2225104Y714447D01*
X2224012Y715613D01*
X2222484Y716196D01*
X2220955Y715905D01*
X2219645Y715030D01*
X2218772Y712988D01*
X2218335Y711238D01*
Y709488D01*
X2218772Y707738D01*
X2219864Y705988D01*
X2221174Y704822D01*
X2222702Y704530D01*
X2224230Y705113D01*
X2225759Y706863D01*
G01X2243477Y722030D02*
Y704530D01*
G01Y707154D02*
X2242604Y705696D01*
X2241293Y704822D01*
X2239765Y704530D01*
X2238019Y705113D01*
X2236709Y706571D01*
X2235835Y708321D01*
X2235617Y710363D01*
X2235835Y712405D01*
X2236709Y714155D01*
X2238019Y715613D01*
X2239765Y716196D01*
X2241293Y715905D01*
X2242385Y715321D01*
X2243477Y714155D01*
G01X2260977Y704530D02*
Y716196D01*
G01Y714155D02*
X2260104Y715321D01*
X2258793Y715905D01*
X2257265Y716196D01*
X2255737Y715613D01*
X2254427Y714447D01*
X2253553Y712697D01*
X2253117Y710363D01*
X2253553Y708030D01*
X2254427Y706280D01*
X2255737Y705113D01*
X2257265Y704530D01*
X2258793Y704822D01*
X2260104Y705696D01*
X2260977Y706863D01*
G01X2270835Y704530D02*
Y716196D01*
G01Y713280D02*
X2271709Y714738D01*
X2273019Y715905D01*
X2274765Y716196D01*
X2276293Y715905D01*
X2277604Y714738D01*
X2278259Y712697D01*
Y704530D01*
G01X2295540Y714738D02*
X2294012Y715905D01*
X2292702Y716196D01*
X2290955Y715613D01*
X2289645Y714447D01*
X2288772Y712405D01*
X2288553Y710363D01*
X2288772Y708321D01*
X2289645Y706571D01*
X2290955Y705113D01*
X2292702Y704530D01*
X2294230Y705113D01*
X2295540Y706280D01*
G01X2306272Y712405D02*
X2313259D01*
X2312604Y714447D01*
X2311512Y715613D01*
X2309984Y716196D01*
X2308455Y715905D01*
X2307145Y715030D01*
X2306272Y712988D01*
X2305835Y711238D01*
Y709488D01*
X2306272Y707738D01*
X2307364Y705988D01*
X2308674Y704822D01*
X2310202Y704530D01*
X2311730Y705113D01*
X2313259Y706863D01*
G01X1854547Y681546D02*
Y669880D01*
G01Y686213D02*
X1854110Y686505D01*
Y687088D01*
X1854547Y687380D01*
X1854984Y687088D01*
Y686505D01*
X1854547Y686213D01*
G01X1868772Y671921D02*
X1869864Y670755D01*
X1871392Y669880D01*
X1872702D01*
X1874012Y670463D01*
X1874885Y671338D01*
X1875322Y672504D01*
X1875104Y674255D01*
X1874230Y675130D01*
X1870300Y676880D01*
X1869427Y678922D01*
X1869864Y680380D01*
X1870737Y681255D01*
X1872047Y681546D01*
X1873357Y681255D01*
X1874667Y680380D01*
G01X1902025Y669880D02*
Y687380D01*
X1912069Y669880D01*
Y687380D01*
G01X1924547Y669880D02*
X1922800Y670172D01*
X1921272Y671338D01*
X1919962Y673088D01*
X1919088Y675130D01*
X1918652Y677463D01*
Y679797D01*
X1919088Y682130D01*
X1919962Y684172D01*
X1921272Y685921D01*
X1922800Y687088D01*
X1924547Y687380D01*
X1926293Y687088D01*
X1927822Y685921D01*
X1929132Y684172D01*
X1930006Y682130D01*
X1930442Y679797D01*
Y677463D01*
X1930006Y675130D01*
X1929132Y673088D01*
X1927822Y671338D01*
X1926293Y670172D01*
X1924547Y669880D01*
G01X1942047Y687380D02*
Y669880D01*
G01X1937025Y687380D02*
X1947069D01*
G01X1973335Y681546D02*
Y673380D01*
X1974209Y671338D01*
X1975519Y670172D01*
X1977047Y669880D01*
X1978575Y670172D01*
X1979885Y671338D01*
X1980759Y673380D01*
G01Y669880D02*
Y681546D01*
G01X1991272Y671921D02*
X1992364Y670755D01*
X1993892Y669880D01*
X1995202D01*
X1996512Y670463D01*
X1997385Y671338D01*
X1997822Y672504D01*
X1997604Y674255D01*
X1996730Y675130D01*
X1992800Y676880D01*
X1991927Y678922D01*
X1992364Y680380D01*
X1993237Y681255D01*
X1994547Y681546D01*
X1995857Y681255D01*
X1997167Y680380D01*
G01X2008772Y677755D02*
X2015759D01*
X2015104Y679797D01*
X2014012Y680963D01*
X2012484Y681546D01*
X2010955Y681255D01*
X2009645Y680380D01*
X2008772Y678338D01*
X2008335Y676588D01*
Y674838D01*
X2008772Y673088D01*
X2009864Y671338D01*
X2011174Y670172D01*
X2012702Y669880D01*
X2014230Y670463D01*
X2015759Y672213D01*
G01X2033477Y687380D02*
Y669880D01*
G01Y672504D02*
X2032604Y671046D01*
X2031293Y670172D01*
X2029765Y669880D01*
X2028019Y670463D01*
X2026709Y671921D01*
X2025835Y673671D01*
X2025617Y675713D01*
X2025835Y677755D01*
X2026709Y679505D01*
X2028019Y680963D01*
X2029765Y681546D01*
X2031293Y681255D01*
X2032385Y680671D01*
X2033477Y679505D01*
G01X3937Y0D02*
X116260D01*
G01X0Y3937D02*
G03X3937Y0I3937J0D01*
G01X0Y723480D02*
Y3937D01*
G01X416Y725241D02*
G03X0Y723480I3521J-1761D01*
G01X18597Y761603D02*
X416Y725241D01*
G01X77756Y98425D02*
G03X63976I-6890J0D01*
G01D02*
G03X77756I6890J0D01*
G01X83071Y245079D02*
G03Y231693I0J-6693D01*
G01X77756Y472441D02*
G03X63976I-6890J0D01*
G01D02*
G03X77756I6890J0D01*
G01X57087Y740157D02*
G03X41339I-7874J0D01*
G01D02*
G03X57087I7874J0D01*
G01X22118Y763780D02*
G03X18597Y761603I1J-3937D01*
G01X386149Y763780D02*
X22118D01*
G01X128071Y3937D02*
G03X132008Y0I3937J0D01*
G01X116260D02*
G03X120197Y3937I0J3937D01*
G01X132008Y0D02*
X275709D01*
G01X120197Y3937D02*
Y429331D01*
G01X128071Y59055D02*
Y3937D01*
G01Y59055D02*
G03X120197I-3937J0D01*
G01X128071D02*
G03X120197I-3937J0D01*
G01X128071Y98425D02*
Y421457D01*
G01X120197Y98425D02*
G03X128071I3937J0D01*
G01X120197D02*
G03X128071I3937J0D01*
G01X96457Y231693D02*
G03Y245079I0J6693D01*
G01X83071D02*
X96457D01*
G01Y231693D02*
X83071D01*
G01X96654Y413583D02*
G03X83661I-6496J0D01*
G01D02*
G03X96654I6496J0D01*
G01X132008Y425394D02*
G03X128071Y421457I0J-3937D01*
G01X124134Y433268D02*
X283583D01*
G01X124134D02*
G03X120197Y429331I0J-3937D01*
G01X184173Y425394D02*
X132008D01*
G01X213480Y37075D02*
G03I-4291J0D01*
G01Y383483D02*
G03I-4291J0D01*
G01X184173Y425394D02*
G03Y433268I0J3937D01*
G01Y425394D02*
G03Y433268I0J3937D01*
G01X171457Y669291D02*
G03X154921I-8268J0D01*
G01D02*
G03X171457I8268J0D01*
G01X223543Y425394D02*
X275709D01*
G01X223543Y433268D02*
G03Y425394I0J-3937D01*
G01Y433268D02*
G03Y425394I0J-3937D01*
G01X275709Y0D02*
G03X279646Y3937I0J3937D01*
G01X291457Y0D02*
X921260D01*
G01X287520Y3937D02*
G03X291457Y0I3937J0D01*
G01X287520Y429331D02*
Y3937D01*
G01X279646Y59055D02*
Y3937D01*
G01X287520Y59055D02*
G03X279646I-3937J0D01*
G01X287520D02*
G03X279646I-3937J0D01*
G01Y98425D02*
Y421457D01*
G01Y98425D02*
G03X287520I3937J0D01*
G01X279646D02*
G03X287520I3937J0D01*
G01X315551Y157677D02*
G03X302559I-6496J0D01*
G01D02*
G03X315551I6496J0D01*
G01X315945Y406890D02*
G03Y420276I0J6693D01*
G01X302559D02*
X315945D01*
G01X302559D02*
G03Y406890I0J-6693D01*
G01X315945D02*
X302559D01*
G01X279646Y421457D02*
G03X275709Y425394I-3937J0D01*
G01X287520Y429331D02*
G03X283583Y433268I-3937J0D01*
G01X321850Y472441D02*
G03X308071I-6889J0D01*
G01D02*
G03X321850I6889J0D01*
G01X412402Y39370D02*
G03X398622I-6890J0D01*
G01D02*
G03X412402I6890J0D01*
G01X371063Y740157D02*
G03X357283I-6890J0D01*
G01D02*
G03X371063I6890J0D01*
G01X403756Y763780D02*
G03X400235Y758082I0J-3937D01*
G01X389671Y761603D02*
G03X386149Y763780I-3522J-1760D01*
G01X414895Y728762D02*
X400235Y758082D01*
G01X407852Y725241D02*
X389671Y761603D01*
G01X403756Y763780D02*
X428096D01*
G01X416142Y200787D02*
G03X420079Y196850I3937J0D01*
G01X408268Y188976D02*
Y723480D01*
G01Y188976D02*
G03X412205I1968J0D01*
G01X556299Y196850D02*
X420079D01*
G01X564173Y188976D02*
X412205D01*
G01X416142Y316929D02*
Y200787D01*
G01Y316929D02*
G03X408268I-3937J0D01*
G01X416142D02*
G03X408268I-3937J0D01*
G01X416142Y347638D02*
Y690803D01*
G01X408268Y347638D02*
G03X416142I3937J0D01*
G01X408268D02*
G03X416142I3937J0D01*
G01Y721512D02*
Y723481D01*
G01Y723482D02*
G03X414894Y728764I-11811J-2D01*
G01X408268Y723480D02*
G03X407852Y725241I-3937J0D01*
G01X408268Y721512D02*
G03X416142I3937J0D01*
G01Y690803D02*
G03X408268I-3937J0D01*
G01Y721512D02*
G03X416142I3937J0D01*
G01Y690803D02*
G03X408268I-3937J0D01*
G01X428096Y763780D02*
G03X435970I3937J0D01*
G01D02*
X572622D01*
G01X483800Y137224D02*
G03X493878I5039J0D01*
G01X493563Y164744D02*
G03X484115I-4724J0D01*
G01D02*
G03X493563I4724J0D01*
G01X493878Y137224D02*
G03X483800I-5039J0D01*
G01X493622Y245605D02*
G03I-4291J0D01*
G01Y698924D02*
G03I-4291J0D01*
G01X556299Y196850D02*
G03X560236Y200787I0J3937D01*
G01X564173Y188976D02*
G03X568110I1968J0D01*
G01Y723480D02*
Y188976D01*
G01X560236Y316929D02*
Y200787D01*
G01X568110Y316929D02*
G03X560236I-3937J0D01*
G01X568110D02*
G03X560236I-3937J0D01*
G01Y690803D02*
Y347638D01*
G01D02*
G03X568110I3937J0D01*
G01X560236D02*
G03X568110I3937J0D01*
G01X560236Y721512D02*
Y723481D01*
G01X561484Y728764D02*
G03X560236Y723482I10563J-5284D01*
G01X568526Y725241D02*
G03X568110Y723480I3521J-1761D01*
G01X560236Y721512D02*
G03X568110I3937J0D01*
G01Y690803D02*
G03X560236I-3937J0D01*
G01Y721512D02*
G03X568110I3937J0D01*
G01Y690803D02*
G03X560236I-3937J0D01*
G01X576143Y758082D02*
G03X572622Y763780I-3521J1761D01*
G01X576143Y758082D02*
X561483Y728762D01*
G01X586707Y761603D02*
X568526Y725241D01*
G01X590228Y763780D02*
G03X586707Y761603I1J-3937D01*
G01X903079Y763780D02*
X590228D01*
G01X634252Y57874D02*
G03X625591I-4331J0D01*
G01D02*
G03X634252I4331J0D01*
G01X658661Y180000D02*
G03X646850I-5905J0D01*
G01D02*
G03X658661I5906J0D01*
G01X619094Y433071D02*
G03X605315I-6889J0D01*
G01D02*
G03X619094I6890J0D01*
G01Y740157D02*
G03X605315I-6889J0D01*
G01D02*
G03X619094I6890J0D01*
G01X712992Y57874D02*
G03X704331I-4331J0D01*
G01D02*
G03X712992I4330J0D01*
G01X859449Y332598D02*
G03X871260I5905J0D01*
G01D02*
G03X859449I-5906J0D01*
G01X921260Y0D02*
G03X925197Y3937I0J3937D01*
G01X883858Y59055D02*
G03X868110I-7874J0D01*
G01D02*
G03X883858I7874J0D01*
G01X925197Y3937D02*
Y723480D01*
G01X882874Y433071D02*
G03X869094I-6890J0D01*
G01D02*
G03X882874I6890J0D01*
G01X925197Y723480D02*
G03X924781Y725241I-3937J0D01*
G01X882874Y740157D02*
G03X869094I-6890J0D01*
G01D02*
G03X882874I6890J0D01*
G01X906600Y761603D02*
G03X903079Y763780I-3522J-1760D01*
G01X924781Y725241D02*
X906600Y761603D01*
G54D13*
G01X261617Y608900D02*
X259747D01*
G01X259623Y607600D02*
X261078D01*
G01X263917Y606600D02*
X261617Y608900D01*
G01X261078Y607600D02*
X263378Y605300D01*
G01X283853Y606600D02*
X263917D01*
G01X263378Y605300D02*
X284392D01*
G01X263378D02*
X284392D01*
G01X283853Y606600D02*
X263917D01*
G01X261078Y607600D02*
X263378Y605300D01*
G01X263917Y606600D02*
X261617Y608900D01*
G01X259623Y607600D02*
X261078D01*
G01X261617Y608900D02*
X259747D01*
G01X272213Y600425D02*
X252419D01*
G01X272752Y599125D02*
X252333D01*
G01X273141Y601353D02*
X272213Y600425D01*
G01X273680Y600053D02*
X272752Y599125D01*
G01X280415Y601353D02*
X273141D01*
G01X290354Y600053D02*
X273680D01*
G01X290354D02*
X273680D01*
G01X290354D02*
X273680D01*
G01X272752Y599125D02*
X252333D01*
G01X272213Y600425D02*
X252419D01*
G01X273680Y600053D02*
X272752Y599125D01*
G01X273141Y601353D02*
X272213Y600425D01*
G01X290354Y600053D02*
X273680D01*
G01X280415Y601353D02*
X273141D01*
G01X338543Y322774D02*
X329282D01*
G01Y324074D02*
X338543D01*
G01X340699Y321881D02*
G03X338543Y322774I-2156J-2157D01*
G01Y324074D02*
G02X341619Y322801I1J-4350D01*
G01X338543Y324074D02*
G02X341619Y322801I1J-4350D01*
G01X340699Y321881D02*
G03X338543Y322774I-2156J-2157D01*
G01X329282Y324074D02*
X338543D01*
G01Y322774D02*
X329282D01*
G01X339479Y310174D02*
X335682D01*
G01X339479Y311474D02*
X335682D01*
G01X341327Y309408D02*
G03X339479Y310174I-1849J-1849D01*
G01X342247Y310328D02*
G03X339479Y311474I-2768J-2770D01*
G01D02*
X335682D01*
G01X339479Y310174D02*
X335682D01*
G01X342247Y310328D02*
G03X339479Y311474I-2768J-2770D01*
G01X341327Y309408D02*
G03X339479Y310174I-1849J-1849D01*
G01X340315Y297577D02*
X329282D01*
G01X340315Y298877D02*
X329282D01*
G01X340315D02*
X329282D01*
G01X340315Y297577D02*
X329282D01*
G01X343110Y284884D02*
X335682D01*
G01X343110Y286184D02*
X335682D01*
G01X343110D02*
X335682D01*
G01X343110Y284884D02*
X335682D01*
G01X337629Y372422D02*
X343196Y366854D01*
G01X338549Y373342D02*
X344217Y367672D01*
G01X335903Y373137D02*
G02X337629Y372422I0J-2441D01*
G01X335903Y374437D02*
G02X338549Y373342I1J-3741D01*
G01X329132Y373137D02*
X335903D01*
G01X329132Y374437D02*
X335903D01*
G01X338549Y373342D02*
X344217Y367672D01*
G01X337629Y372422D02*
X343196Y366854D01*
G01X335903Y374437D02*
G02X338549Y373342I1J-3741D01*
G01X335903Y373137D02*
G02X337629Y372422I0J-2441D01*
G01X329132Y374437D02*
X335903D01*
G01X329132Y373137D02*
X335903D01*
G01X339995Y359994D02*
X340838Y359151D01*
G01X338598Y360574D02*
G02X339995Y359994I-1J-1976D01*
G01X338598Y361874D02*
G02X340915Y360914I0J-3276D01*
G01X335682Y360574D02*
X338598D01*
G01X335682Y361874D02*
X338598D01*
G01X339995Y359994D02*
X340838Y359151D01*
G01X338598Y361874D02*
G02X340915Y360914I0J-3276D01*
G01X338598Y360574D02*
G02X339995Y359994I-1J-1976D01*
G01X335682Y361874D02*
X338598D01*
G01X335682Y360574D02*
X338598D01*
G01X339817Y347971D02*
X329282D01*
G01X339817Y349271D02*
X329282D01*
G01X340922Y347512D02*
G03X339817Y347971I-1106J-1104D01*
G01X341842Y348432D02*
G03X339817Y349271I-2025J-2024D01*
G01D02*
X329282D01*
G01X339817Y347971D02*
X329282D01*
G01X341842Y348432D02*
G03X339817Y349271I-2025J-2024D01*
G01X340922Y347512D02*
G03X339817Y347971I-1106J-1104D01*
G01X339199Y335371D02*
X335682D01*
G01Y336671D02*
X339199D01*
G01X341178Y334551D02*
G03X339199Y335371I-1980J-1981D01*
G01Y336671D02*
G02X342098Y335471I0J-4102D01*
G01X339199Y336671D02*
G02X342098Y335471I0J-4102D01*
G01X341178Y334551D02*
G03X339199Y335371I-1980J-1981D01*
G01X335682Y336671D02*
X339199D01*
G01Y335371D02*
X335682D01*
G01X294661Y617408D02*
X283853Y606600D01*
G01X284392Y605300D02*
X295200Y616108D01*
G01X323922Y617408D02*
X294661D01*
G01X320856Y616108D02*
X323383D01*
G01X316156D02*
X317806D01*
G01X311456D02*
X313106D01*
G01X306756D02*
X308406D01*
G01X295200D02*
X303706D01*
G01X333830Y607500D02*
X323922Y617408D01*
G01X332124Y607367D02*
X333291Y606200D01*
G01X331134Y607367D02*
X332124D01*
G01X328801Y610690D02*
X329968Y609523D01*
G01X327811Y610690D02*
X328801D01*
G01X323383Y616108D02*
X326644Y612847D01*
G01X335789Y607500D02*
X333830D01*
G01X333291Y606200D02*
X335250D01*
G01X337534Y605755D02*
X335789Y607500D01*
G01X335250Y606200D02*
X336234Y605216D01*
G01X337534Y604238D02*
Y605755D01*
G01X336234Y605216D02*
Y604237D01*
G01Y605216D02*
Y604237D01*
G01X337534Y604238D02*
Y605755D01*
G01X335250Y606200D02*
X336234Y605216D01*
G01X337534Y605755D02*
X335789Y607500D01*
G01X333291Y606200D02*
X335250D01*
G01X335789Y607500D02*
X333830D01*
G01X332124Y607367D02*
X333291Y606200D01*
G01X333830Y607500D02*
X323922Y617408D01*
G01X331134Y607367D02*
X332124D01*
G01X333830Y607500D02*
X323922Y617408D01*
G01X328801Y610690D02*
X329968Y609523D01*
G01X333830Y607500D02*
X323922Y617408D01*
G01X327811Y610690D02*
X328801D01*
G01X333830Y607500D02*
X323922Y617408D01*
G01X323383Y616108D02*
X326644Y612847D01*
G01X333830Y607500D02*
X323922Y617408D01*
G01X320856Y616108D02*
X323383D01*
G01X323922Y617408D02*
X294661D01*
G01X316156Y616108D02*
X317806D01*
G01X323922Y617408D02*
X294661D01*
G01X311456Y616108D02*
X313106D01*
G01X323922Y617408D02*
X294661D01*
G01X306756Y616108D02*
X308406D01*
G01X323922Y617408D02*
X294661D01*
G01X295200Y616108D02*
X303706D01*
G01X323922Y617408D02*
X294661D01*
G01X284392Y605300D02*
X295200Y616108D01*
G01X294661Y617408D02*
X283853Y606600D01*
G01X285115Y601353D02*
X283465D01*
G01X289815D02*
X288165D01*
G01X299262Y610800D02*
X289815Y601353D01*
G01X299801Y609500D02*
X290354Y600053D01*
G01X300912Y610800D02*
X299262D01*
G01X316754Y609500D02*
X299801D01*
G01X305612Y610800D02*
X303962D01*
G01X316754Y609500D02*
X299801D01*
G01X310312Y610800D02*
X308662D01*
G01X316754Y609500D02*
X299801D01*
G01X317293Y610800D02*
X313362D01*
G01X316754Y609500D02*
X299801D01*
G01X318460Y609633D02*
X317293Y610800D01*
G01X327345Y598909D02*
X316754Y609500D01*
G01X321783Y606310D02*
X320616Y607477D01*
G01X327345Y598909D02*
X316754Y609500D01*
G01X327884Y600209D02*
X323940Y604153D01*
G01X327345Y598909D02*
X316754Y609500D01*
G01X332947Y600209D02*
X327884D01*
G01X332408Y598909D02*
X327345D01*
G01X333556Y599600D02*
X332947Y600209D01*
G01X333017Y598300D02*
X332408Y598909D01*
G01X343300Y599600D02*
X333556D01*
G01X343839Y598300D02*
X333017D01*
G01X285115Y601353D02*
X283465D01*
G01X289815D02*
X288165D01*
G01X299801Y609500D02*
X290354Y600053D01*
G01X299262Y610800D02*
X289815Y601353D01*
G01X316754Y609500D02*
X299801D01*
G01X300912Y610800D02*
X299262D01*
G01X305612D02*
X303962D01*
G01X310312D02*
X308662D01*
G01X317293D02*
X313362D01*
G01X327345Y598909D02*
X316754Y609500D01*
G01X318460Y609633D02*
X317293Y610800D01*
G01X321783Y606310D02*
X320616Y607477D01*
G01X327884Y600209D02*
X323940Y604153D01*
G01X332408Y598909D02*
X327345D01*
G01X332947Y600209D02*
X327884D01*
G01X333017Y598300D02*
X332408Y598909D01*
G01X333556Y599600D02*
X332947Y600209D01*
G01X343839Y598300D02*
X333017D01*
G01X343300Y599600D02*
X333556D01*
G01X402464Y133807D02*
X420377Y121917D01*
G01X385599Y146563D02*
X420770Y123217D01*
G01X384664Y145622D02*
X402464Y133806D01*
G01X385599Y146563D02*
X420770Y123217D01*
G01X385599Y146563D02*
X420770Y123217D01*
G01X402464Y133807D02*
X420377Y121917D01*
G01X384664Y145622D02*
X402464Y133806D01*
G01X419806Y117328D02*
X381241Y142846D01*
G01X420198Y118628D02*
X382178Y143786D01*
G01X420198Y118628D02*
X382178Y143786D01*
G01X419806Y117328D02*
X381241Y142846D01*
G01X378234Y142181D02*
X398345Y128870D01*
G01X397627Y127786D02*
X387571Y134442D01*
G01X378234Y142181D02*
X398345Y128870D01*
G01X418066Y114258D02*
X397627Y127786D01*
G01X398345Y128870D02*
X418458Y115558D01*
G01X398345Y128870D02*
X418458Y115558D01*
G01X418066Y114258D02*
X397627Y127786D01*
G01X378234Y142181D02*
X398345Y128870D01*
G01X397627Y127786D02*
X387571Y134442D01*
G01X414589Y111118D02*
X373859Y138071D01*
G01X374798Y139010D02*
X414981Y112418D01*
G01X374798Y139010D02*
X414981Y112418D01*
G01X414589Y111118D02*
X373859Y138071D01*
G01X405484Y112413D02*
X371363Y134997D01*
G01X412542Y109301D02*
X372300Y135937D01*
G01X412150Y108001D02*
X405484Y112413D01*
G01X412542Y109301D02*
X372300Y135937D01*
G01X412542Y109301D02*
X372300Y135937D01*
G01X405484Y112413D02*
X371363Y134997D01*
G01X412150Y108001D02*
X405484Y112413D01*
G01X367477Y133093D02*
X360660Y143289D01*
G01X410216Y104815D02*
X367477Y133093D01*
G01X410608Y106115D02*
X368413Y134034D01*
G01X367477Y133093D02*
X360660Y143289D01*
G01X410608Y106115D02*
X368413Y134034D01*
G01X410216Y104815D02*
X367477Y133093D01*
G01X366609Y130173D02*
X358256Y142659D01*
G01X365673Y129232D02*
X361352Y135693D01*
G01X366609Y130173D02*
X358256Y142659D01*
G01X407223Y101743D02*
X365673Y129232D01*
G01X407615Y103043D02*
X366609Y130173D01*
G01D02*
X358256Y142659D01*
G01X365673Y129232D02*
X361352Y135693D01*
G01X407615Y103043D02*
X366609Y130173D01*
G01X407223Y101743D02*
X365673Y129232D01*
G01X394061Y143880D02*
X407280D01*
G01X394600Y145180D02*
X406741D01*
G01X393680Y144261D02*
X394061Y143880D01*
G01X388487Y151293D02*
X394600Y145180D01*
G01X387476Y150464D02*
X393680Y144260D01*
G01X388487Y151293D02*
X394600Y145180D01*
G01X384566Y154824D02*
X387476Y150464D01*
G01X385791Y155332D02*
X388487Y151293D01*
G01X378560Y184880D02*
X384566Y154824D01*
G01X379886Y184880D02*
X385791Y155332D01*
G01X385875Y221461D02*
X378560Y184881D01*
G01X387201Y221461D02*
X379886Y184880D01*
G01X394600Y145180D02*
X406741D01*
G01X394061Y143880D02*
X407280D01*
G01X388487Y151293D02*
X394600Y145180D01*
G01X393680Y144261D02*
X394061Y143880D01*
G01X387476Y150464D02*
X393680Y144260D01*
G01X385791Y155332D02*
X388487Y151293D01*
G01X384566Y154824D02*
X387476Y150464D01*
G01X379886Y184880D02*
X385791Y155332D01*
G01X378560Y184880D02*
X384566Y154824D01*
G01X387201Y221461D02*
X379886Y184880D01*
G01X385875Y221461D02*
X378560Y184881D01*
G01X381745Y149959D02*
X384664Y145622D01*
G01X382969Y150469D02*
X385599Y146563D01*
G01X375094Y183194D02*
X381745Y149959D01*
G01X379696Y166830D02*
X382969Y150469D01*
G01X376420Y183194D02*
X379695Y166830D01*
G01X382654Y220982D02*
X375094Y183194D01*
G01X383980Y220982D02*
X376420Y183194D01*
G01X382969Y150469D02*
X385599Y146563D01*
G01X381745Y149959D02*
X384664Y145622D01*
G01X379696Y166830D02*
X382969Y150469D01*
G01X375094Y183194D02*
X381745Y149959D01*
G01X376420Y183194D02*
X379695Y166830D01*
G01X375094Y183194D02*
X381745Y149959D01*
G01X383980Y220982D02*
X376420Y183194D01*
G01X382654Y220982D02*
X375094Y183194D01*
G01X371679Y182607D02*
X379305Y220733D01*
G01X372954Y182352D02*
X380631Y220733D01*
G01X378792Y146519D02*
X371628Y182351D01*
G01X380017Y147027D02*
X372954Y182351D01*
G01X381241Y142846D02*
X378792Y146519D01*
G01X382178Y143786D02*
X380017Y147027D01*
G01X372954Y182352D02*
X380631Y220733D01*
G01X371679Y182607D02*
X379305Y220733D01*
G01X380017Y147027D02*
X372954Y182351D01*
G01X378792Y146519D02*
X371628Y182351D01*
G01X382178Y143786D02*
X380017Y147027D01*
G01X381241Y142846D02*
X378792Y146519D01*
G01X364084Y181351D02*
X373635Y229103D01*
G01X374961D02*
X365410Y181351D01*
G01X369875Y152376D02*
X364084Y181351D01*
G01X365410D02*
X371100Y152883D01*
G01X377297Y141241D02*
X369875Y152376D01*
G01X371100Y152883D02*
X378234Y142181D01*
G01X387571Y134442D02*
X377297Y141241D01*
G01X387571Y134442D02*
X377297Y141241D01*
G01X371100Y152883D02*
X378234Y142181D01*
G01X377297Y141241D02*
X369875Y152376D01*
G01X365410Y181351D02*
X371100Y152883D01*
G01X369875Y152376D02*
X364084Y181351D01*
G01X374961Y229103D02*
X365410Y181351D01*
G01X364084D02*
X373635Y229103D01*
G01X360472Y180085D02*
X369922Y227345D01*
G01X371222Y227216D02*
X361798Y180085D01*
G01X366709Y148883D02*
X360472Y180085D01*
G01X361798D02*
X367934Y149388D01*
G01X369874Y144096D02*
X366709Y148883D01*
G01X367934Y149388D02*
X370959Y144814D01*
G01X371819Y141155D02*
X369874Y144096D01*
G01X370959Y144814D02*
X374798Y139010D01*
G01X372899Y139523D02*
X371819Y141155D01*
G01X370959Y144814D02*
X374798Y139010D01*
G01X373859Y138071D02*
X372899Y139523D01*
G01X370959Y144814D02*
X374798Y139010D01*
G01X370959Y144814D02*
X374798Y139010D01*
G01X371819Y141155D02*
X369874Y144096D01*
G01X372899Y139523D02*
X371819Y141155D01*
G01X373859Y138071D02*
X372899Y139523D01*
G01X367934Y149388D02*
X370959Y144814D01*
G01X369874Y144096D02*
X366709Y148883D01*
G01X361798Y180085D02*
X367934Y149388D01*
G01X366709Y148883D02*
X360472Y180085D01*
G01X371222Y227216D02*
X361798Y180085D01*
G01X360472D02*
X369922Y227345D01*
G01X357127Y179364D02*
X362110Y204282D01*
G01X358453Y179364D02*
X363385Y204027D01*
G01X363698Y146493D02*
X357127Y179364D01*
G01X364923Y147000D02*
X358453Y179364D01*
G01X364763Y144896D02*
X363698Y146493D01*
G01X366766Y144235D02*
X364923Y147000D01*
G01X365552Y143711D02*
X364763Y144896D01*
G01X366766Y144235D02*
X364923Y147000D01*
G01X367529Y140748D02*
X365552Y143711D01*
G01X368611Y141469D02*
X366766Y144235D01*
G01X371363Y134997D02*
X367529Y140748D01*
G01X372300Y135937D02*
X368611Y141469D01*
G01X358453Y179364D02*
X363385Y204027D01*
G01X357127Y179364D02*
X362110Y204282D01*
G01X364923Y147000D02*
X358453Y179364D01*
G01X363698Y146493D02*
X357127Y179364D01*
G01X366766Y144235D02*
X364923Y147000D01*
G01X364763Y144896D02*
X363698Y146493D01*
G01X365552Y143711D02*
X364763Y144896D01*
G01X368611Y141469D02*
X366766Y144235D01*
G01X367529Y140748D02*
X365552Y143711D01*
G01X372300Y135937D02*
X368611Y141469D01*
G01X371363Y134997D02*
X367529Y140748D01*
G01X354972Y198291D02*
X358895Y218477D01*
G01X356297Y198291D02*
X360220Y218477D01*
G01X356013Y192939D02*
X354972Y198291D01*
G01X357338Y192939D02*
X356297Y198291D01*
G01X353409Y179544D02*
X356013Y192939D01*
G01X354735Y179548D02*
X357338Y192939D01*
G01X360660Y143289D02*
X353409Y179544D01*
G01X361885Y143797D02*
X354735Y179548D01*
G01X368413Y134034D02*
X361885Y143797D01*
G01X356297Y198291D02*
X360220Y218477D01*
G01X354972Y198291D02*
X358895Y218477D01*
G01X357338Y192939D02*
X356297Y198291D01*
G01X356013Y192939D02*
X354972Y198291D01*
G01X354735Y179548D02*
X357338Y192939D01*
G01X353409Y179544D02*
X356013Y192939D01*
G01X361885Y143797D02*
X354735Y179548D01*
G01X360660Y143289D02*
X353409Y179544D01*
G01X368413Y134034D02*
X361885Y143797D01*
G01X352021Y191568D02*
X350452Y199635D01*
G01X353346Y191568D02*
X351777Y199635D01*
G01X349622Y179236D02*
X352021Y191568D01*
G01X350948Y179239D02*
X353346Y191568D01*
G01X357031Y142151D02*
X349622Y179236D01*
G01X358256Y142659D02*
X350948Y179239D01*
G01X361352Y135693D02*
X357031Y142151D01*
G01X353346Y191568D02*
X351777Y199635D01*
G01X352021Y191568D02*
X350452Y199635D01*
G01X350948Y179239D02*
X353346Y191568D01*
G01X349622Y179236D02*
X352021Y191568D01*
G01X358256Y142659D02*
X350948Y179239D01*
G01X357031Y142151D02*
X349622Y179236D01*
G01X361352Y135693D02*
X357031Y142151D01*
G01X363062Y335525D02*
X385875Y221461D01*
G01X364290Y336017D02*
X387201Y221461D01*
G01X364290Y336017D02*
X387201Y221461D01*
G01X363062Y335525D02*
X385875Y221461D01*
G01X361102Y328726D02*
X382654Y220982D01*
G01X362327Y329233D02*
X383980Y220982D01*
G01X362327Y329233D02*
X383980Y220982D01*
G01X361102Y328726D02*
X382654Y220982D01*
G01X379305Y220733D02*
X359334Y320599D01*
G01X380631Y220733D02*
X360559Y321107D01*
G01X380631Y220733D02*
X360559Y321107D01*
G01X379305Y220733D02*
X359334Y320599D01*
G01X373565Y229452D02*
X357402Y310444D01*
G01X374840Y229707D02*
X374961Y229103D01*
G01X358627Y310951D02*
X374840Y229707D01*
G01X373635Y229103D02*
X373565Y229452D01*
G01X374840Y229707D02*
X374961Y229103D01*
G01X358627Y310951D02*
X374840Y229707D01*
G01D02*
X374961Y229103D01*
G01X373565Y229452D02*
X357402Y310444D01*
G01X373635Y229103D02*
X373565Y229452D01*
G01X358627Y310951D02*
X374840Y229707D01*
G01X373565Y229452D02*
X357402Y310444D01*
G01X373635Y229103D02*
X373565Y229452D01*
G01X369922Y227880D02*
X355210Y301435D01*
G01X356435Y301943D02*
X371222Y228009D01*
G01X369922Y227345D02*
Y227880D01*
G01X371222Y228009D02*
Y227216D01*
G01Y228009D02*
Y227216D01*
G01X369922Y227345D02*
Y227880D01*
G01X356435Y301943D02*
X371222Y228009D01*
G01X369922Y227880D02*
X355210Y301435D01*
G01X366736Y228121D02*
X354213Y290778D01*
G01X368036Y228250D02*
X355438Y291285D01*
G01X366736Y227414D02*
Y228121D01*
G01X368036Y227285D02*
Y228250D01*
G01X362110Y204282D02*
X366736Y227414D01*
G01X363385Y204027D02*
X368036Y227285D01*
G01Y228250D02*
X355438Y291285D01*
G01X366736Y228121D02*
X354213Y290778D01*
G01X368036Y227285D02*
Y228250D01*
G01X366736Y227414D02*
Y228121D01*
G01X363385Y204027D02*
X368036Y227285D01*
G01X362110Y204282D02*
X366736Y227414D01*
G01X358355Y246942D02*
X350222Y287644D01*
G01X359681Y246943D02*
X351447Y288152D01*
G01X355835Y234225D02*
X358355Y246942D01*
G01X357160Y234223D02*
X359681Y246943D01*
G01X358895Y218477D02*
X355835Y234225D01*
G01X360220Y218477D02*
X357160Y234223D01*
G01X359681Y246943D02*
X351447Y288152D01*
G01X358355Y246942D02*
X350222Y287644D01*
G01X357160Y234223D02*
X359681Y246943D01*
G01X355835Y234225D02*
X358355Y246942D01*
G01X360220Y218477D02*
X357160Y234223D01*
G01X358895Y218477D02*
X355835Y234225D01*
G01X354159Y249706D02*
X348022Y280384D01*
G01X355485Y249707D02*
X349247Y280891D01*
G01X351353Y235536D02*
X354159Y249706D01*
G01X352678Y235534D02*
X355485Y249707D01*
G01X354389Y219906D02*
X351353Y235536D01*
G01X355714Y219906D02*
X352678Y235534D01*
G01X350452Y199635D02*
X354389Y219906D01*
G01X351777Y199635D02*
X355714Y219906D01*
G01X355485Y249707D02*
X349247Y280891D01*
G01X354159Y249706D02*
X348022Y280384D01*
G01X352678Y235534D02*
X355485Y249707D01*
G01X351353Y235536D02*
X354159Y249706D01*
G01X355714Y219906D02*
X352678Y235534D01*
G01X354389Y219906D02*
X351353Y235536D01*
G01X351777Y199635D02*
X355714Y219906D01*
G01X350452Y199635D02*
X354389Y219906D01*
G01X340838Y359151D02*
X361102Y328726D01*
G01X341846Y359983D02*
X362327Y329233D01*
G01X341846Y359983D02*
X362327Y329233D01*
G01X340838Y359151D02*
X361102Y328726D01*
G01X359334Y320599D02*
X342329Y346105D01*
G01X360559Y321107D02*
X343338Y346936D01*
G01X360559Y321107D02*
X343338Y346936D01*
G01X359334Y320599D02*
X342329Y346105D01*
G01X353460Y316356D02*
X341639Y334090D01*
G01X342650Y334919D02*
X350602Y322988D01*
G01X357402Y310444D02*
X353460Y316356D01*
G01X350602Y322988D02*
X358627Y310951D01*
G01X350602Y322988D02*
X358627Y310951D01*
G01X357402Y310444D02*
X353460Y316356D01*
G01X342650Y334919D02*
X350602Y322988D01*
G01X353460Y316356D02*
X341639Y334090D01*
G01X343340Y319240D02*
X340699Y321881D01*
G01X341619Y322801D02*
X344351Y320069D01*
G01X355210Y301435D02*
X343340Y319240D01*
G01X344351Y320069D02*
X356435Y301943D01*
G01X344351Y320069D02*
X356435Y301943D01*
G01X355210Y301435D02*
X343340Y319240D01*
G01X341619Y322801D02*
X344351Y320069D01*
G01X343340Y319240D02*
X340699Y321881D01*
G01X342742Y307993D02*
X341327Y309408D01*
G01X343752Y308823D02*
X342247Y310328D01*
G01X345412Y303987D02*
X342742Y307993D01*
G01X351834Y296693D02*
X343752Y308823D01*
G01X350752Y295972D02*
X345412Y303987D01*
G01X351834Y296693D02*
X343752Y308823D01*
G01X352482Y293376D02*
X350752Y295972D01*
G01X355438Y291285D02*
X351834Y296693D01*
G01X354213Y290778D02*
X352482Y293376D01*
G01X355438Y291285D02*
X351834Y296693D01*
G01X343752Y308823D02*
X342247Y310328D01*
G01X342742Y307993D02*
X341327Y309408D01*
G01X351834Y296693D02*
X343752Y308823D01*
G01X345412Y303987D02*
X342742Y307993D01*
G01X350752Y295972D02*
X345412Y303987D01*
G01X355438Y291285D02*
X351834Y296693D01*
G01X352482Y293376D02*
X350752Y295972D01*
G01X354213Y290778D02*
X352482Y293376D01*
G01X342825Y296537D02*
G03X340315Y297577I-2511J-2510D01*
G01X343744Y297458D02*
G03X340315Y298877I-3428J-3432D01*
G01X347215Y292147D02*
X342825Y296537D01*
G01X348225Y292976D02*
X343744Y297457D01*
G01X350222Y287644D02*
X347215Y292147D01*
G01X351447Y288152D02*
X348225Y292976D01*
G01X343744Y297458D02*
G03X340315Y298877I-3428J-3432D01*
G01X342825Y296537D02*
G03X340315Y297577I-2511J-2510D01*
G01X348225Y292976D02*
X343744Y297457D01*
G01X347215Y292147D02*
X342825Y296537D01*
G01X351447Y288152D02*
X348225Y292976D01*
G01X350222Y287644D02*
X347215Y292147D01*
G01X344942Y284124D02*
G03X343110Y284884I-1833J-1831D01*
G01X345862Y285044D02*
G03X343110Y286184I-2752J-2752D01*
G01X346704Y282362D02*
X344942Y284124D01*
G01X347715Y283191D02*
X345862Y285044D01*
G01X348022Y280384D02*
X346704Y282362D01*
G01X349248Y280892D02*
X347715Y283191D01*
G01X345862Y285044D02*
G03X343110Y286184I-2752J-2752D01*
G01X344942Y284124D02*
G03X343110Y284884I-1833J-1831D01*
G01X347715Y283191D02*
X345862Y285044D01*
G01X346704Y282362D02*
X344942Y284124D01*
G01X349248Y280892D02*
X347715Y283191D01*
G01X348022Y280384D02*
X346704Y282362D01*
G01X343196Y366854D02*
X363062Y335525D01*
G01X344217Y367672D02*
X364290Y336017D01*
G01X344217Y367672D02*
X364290Y336017D01*
G01X343196Y366854D02*
X363062Y335525D01*
G01X340915Y360914D02*
X341846Y359983D01*
G01X340915Y360914D02*
X341846Y359983D01*
G01X342329Y346105D02*
X340922Y347512D01*
G01X343338Y346936D02*
X341842Y348432D01*
G01X343338Y346936D02*
X341842Y348432D01*
G01X342329Y346105D02*
X340922Y347512D01*
G01X341639Y334090D02*
X341178Y334551D01*
G01X342098Y335471D02*
X342650Y334919D01*
G01X342098Y335471D02*
X342650Y334919D01*
G01X341639Y334090D02*
X341178Y334551D01*
G01X344700Y601000D02*
X343300Y599600D01*
G01X346000Y600461D02*
X343839Y598300D01*
G01X344700Y613000D02*
Y601000D01*
G01X346000Y613539D02*
Y600461D01*
G01X343189Y614511D02*
X344700Y613000D01*
G01X343728Y615811D02*
X346000Y613539D01*
G01X341077Y614511D02*
X343189D01*
G01X340822Y615811D02*
X343728D01*
G01X346000Y600461D02*
X343839Y598300D01*
G01X344700Y601000D02*
X343300Y599600D01*
G01X346000Y613539D02*
Y600461D01*
G01X344700Y613000D02*
Y601000D01*
G01X343728Y615811D02*
X346000Y613539D01*
G01X343189Y614511D02*
X344700Y613000D01*
G01X340822Y615811D02*
X343728D01*
G01X341077Y614511D02*
X343189D01*
G01X425847Y124641D02*
Y140811D01*
G01X424547Y125180D02*
Y140811D01*
G01X423123Y121917D02*
X425847Y124641D01*
G01X422584Y123217D02*
X424547Y125180D01*
G01X420377Y121917D02*
X423123D01*
G01X420770Y123217D02*
X422584D01*
G01X424547Y125180D02*
Y140811D01*
G01X425847Y124641D02*
Y140811D01*
G01X422584Y123217D02*
X424547Y125180D01*
G01X423123Y121917D02*
X425847Y124641D01*
G01X420770Y123217D02*
X422584D01*
G01X420377Y121917D02*
X423123D01*
G01X430428Y117328D02*
X419806D01*
G01X429889Y118628D02*
X420198D01*
G01X432934Y119834D02*
X430428Y117328D01*
G01X431634Y120373D02*
X429889Y118628D01*
G01X432934Y145535D02*
Y119834D01*
G01X431634Y145535D02*
Y120373D01*
G01X429889Y118628D02*
X420198D01*
G01X430428Y117328D02*
X419806D01*
G01X431634Y120373D02*
X429889Y118628D01*
G01X432934Y119834D02*
X430428Y117328D01*
G01X431634Y145535D02*
Y120373D01*
G01X432934Y145535D02*
Y119834D01*
G01X434959Y114258D02*
X418066D01*
G01X418458Y115558D02*
X434420D01*
G01X440020Y119319D02*
X434959Y114258D01*
G01X434420Y115558D02*
X438720Y119858D01*
G01X440020Y140811D02*
Y119319D01*
G01X438720Y119858D02*
Y140811D01*
G01Y119858D02*
Y140811D01*
G01X440020D02*
Y119319D01*
G01X434420Y115558D02*
X438720Y119858D01*
G01X440020Y119319D02*
X434959Y114258D01*
G01X418458Y115558D02*
X434420D01*
G01X434959Y114258D02*
X418066D01*
G01X440557Y111118D02*
X414589D01*
G01X414981Y112418D02*
X440018D01*
G01X447107Y117668D02*
X440557Y111118D01*
G01X440018Y112418D02*
X445807Y118207D01*
G01X447107Y145535D02*
Y117668D01*
G01X445807Y118207D02*
Y145535D01*
G01Y118207D02*
Y145535D01*
G01X447107D02*
Y117668D01*
G01X440018Y112418D02*
X445807Y118207D01*
G01X447107Y117668D02*
X440557Y111118D01*
G01X414981Y112418D02*
X440018D01*
G01X440557Y111118D02*
X414589D01*
G01X443001Y108001D02*
X412150D01*
G01X442462Y109301D02*
X412542D01*
G01X454193Y119193D02*
X443001Y108001D01*
G01X452893Y119732D02*
X442462Y109301D01*
G01X454193Y140811D02*
Y119193D01*
G01X452893Y140811D02*
Y119732D01*
G01X442462Y109301D02*
X412542D01*
G01X443001Y108001D02*
X412150D01*
G01X452893Y119732D02*
X442462Y109301D01*
G01X454193Y119193D02*
X443001Y108001D01*
G01X452893Y140811D02*
Y119732D01*
G01X454193Y140811D02*
Y119193D01*
G01X446354Y104815D02*
X410216D01*
G01X445815Y106115D02*
X410608D01*
G01X461280Y119741D02*
X446354Y104815D01*
G01X459980Y120280D02*
X445815Y106115D01*
G01X461280Y145535D02*
Y119741D01*
G01X459980Y145535D02*
Y120280D01*
G01X445815Y106115D02*
X410608D01*
G01X446354Y104815D02*
X410216D01*
G01X459980Y120280D02*
X445815Y106115D01*
G01X461280Y119741D02*
X446354Y104815D01*
G01X459980Y145535D02*
Y120280D01*
G01X461280Y145535D02*
Y119741D01*
G01X447881Y101743D02*
X407223D01*
G01X447342Y103043D02*
X407615D01*
G01X468367Y122229D02*
X447881Y101743D01*
G01X467067Y122768D02*
X447342Y103043D01*
G01X468367Y140811D02*
Y122229D01*
G01X467067Y140811D02*
Y122768D01*
G01X447342Y103043D02*
X407615D01*
G01X447881Y101743D02*
X407223D01*
G01X467067Y122768D02*
X447342Y103043D01*
G01X468367Y122229D02*
X447881Y101743D01*
G01X467067Y140811D02*
Y122768D01*
G01X468367Y140811D02*
Y122229D01*
G01X410388Y146988D02*
X420850D01*
G01X409849Y148288D02*
X420850D01*
G01X407280Y143880D02*
X410388Y146988D01*
G01X406741Y145180D02*
X409849Y148288D01*
G01D02*
X420850D01*
G01X410388Y146988D02*
X420850D01*
G01X406741Y145180D02*
X409849Y148288D01*
G01X407280Y143880D02*
X410388Y146988D01*
G01X427300Y142264D02*
X428000D01*
G01X427300Y143564D02*
X428000D01*
G01X425847Y140811D02*
G02X427300Y142264I1453J0D01*
G01X424547Y140811D02*
G02X427300Y143564I2753J0D01*
G01D02*
X428000D01*
G01X427300Y142264D02*
X428000D01*
G01X424547Y140811D02*
G02X427300Y143564I2753J0D01*
G01X425847Y140811D02*
G02X427300Y142264I1453J0D01*
G01X434387Y146988D02*
G03X432934Y145535I0J-1453D01*
G01X434387Y148288D02*
G03X431634Y145535I0J-2753D01*
G01X435087Y146988D02*
X434387D01*
G01X435087Y148288D02*
X434387D01*
G01D02*
G03X431634Y145535I0J-2753D01*
G01X434387Y146988D02*
G03X432934Y145535I0J-1453D01*
G01X435087Y148288D02*
X434387D01*
G01X435087Y146988D02*
X434387D01*
G01X441473Y142264D02*
G03X440020Y140811I0J-1453D01*
G01X438720D02*
G02X441473Y143564I2753J0D01*
G01X442173Y142264D02*
X441473D01*
G01Y143564D02*
X442173D01*
G01X441473D02*
X442173D01*
G01Y142264D02*
X441473D01*
G01X438720Y140811D02*
G02X441473Y143564I2753J0D01*
G01Y142264D02*
G03X440020Y140811I0J-1453D01*
G01X448560Y146988D02*
G03X447107Y145535I0J-1453D01*
G01X445807D02*
G02X448560Y148288I2753J0D01*
G01X449260Y146988D02*
X448560D01*
G01Y148288D02*
X449260D01*
G01X448560D02*
X449260D01*
G01Y146988D02*
X448560D01*
G01X445807Y145535D02*
G02X448560Y148288I2753J0D01*
G01Y146988D02*
G03X447107Y145535I0J-1453D01*
G01X455646Y142264D02*
G03X454193Y140811I0J-1453D01*
G01X455646Y143564D02*
G03X452893Y140811I0J-2753D01*
G01X456346Y142264D02*
X455646D01*
G01X456346Y143564D02*
X455646D01*
G01D02*
G03X452893Y140811I0J-2753D01*
G01X455646Y142264D02*
G03X454193Y140811I0J-1453D01*
G01X456346Y143564D02*
X455646D01*
G01X456346Y142264D02*
X455646D01*
G01X462733Y146988D02*
G03X461280Y145535I0J-1453D01*
G01X462733Y148288D02*
G03X459980Y145535I0J-2753D01*
G01X463433Y146988D02*
X462733D01*
G01X463433Y148288D02*
X462733D01*
G01D02*
G03X459980Y145535I0J-2753D01*
G01X462733Y146988D02*
G03X461280Y145535I0J-1453D01*
G01X463433Y148288D02*
X462733D01*
G01X463433Y146988D02*
X462733D01*
G01X469820Y142264D02*
G03X468367Y140811I0J-1453D01*
G01X469820Y143564D02*
G03X467067Y140811I0J-2753D01*
G01X470520Y142264D02*
X469820D01*
G01X470520Y143564D02*
X469820D01*
G01D02*
G03X467067Y140811I0J-2753D01*
G01X469820Y142264D02*
G03X468367Y140811I0J-1453D01*
G01X470520Y143564D02*
X469820D01*
G01X470520Y142264D02*
X469820D01*
G01X504964Y132827D02*
X505843D01*
G01X503800Y131663D02*
G02X504964Y132827I1164J0D01*
G01Y134127D02*
G03X502500Y131663I0J-2464D01*
G01X503800Y114386D02*
Y131663D01*
G01X502500D02*
Y113847D01*
G01X513750Y104436D02*
X503800Y114386D01*
G01X502500Y113847D02*
X522567Y93780D01*
G01X517073Y101113D02*
X515906Y102280D01*
G01X502500Y113847D02*
X522567Y93780D01*
G01X523106Y95080D02*
X519230Y98956D01*
G01X502500Y113847D02*
X522567Y93780D01*
G01X571330Y95080D02*
X523106D01*
G01X522567Y93780D02*
X571869D01*
G01X522567D02*
X571869D01*
G01X571330Y95080D02*
X523106D01*
G01X502500Y113847D02*
X522567Y93780D01*
G01X513750Y104436D02*
X503800Y114386D01*
G01X517073Y101113D02*
X515906Y102280D01*
G01X523106Y95080D02*
X519230Y98956D01*
G01X502500Y131663D02*
Y113847D01*
G01X503800Y114386D02*
Y131663D01*
G01X504964Y134127D02*
G03X502500Y131663I0J-2464D01*
G01X503800D02*
G02X504964Y132827I1164J0D01*
G01D02*
X505843D01*
G01X512050Y128102D02*
X512929D01*
G01X512050Y129402D02*
X512929D01*
G01X510886Y126938D02*
G02X512050Y128102I1164J0D01*
G01X509586Y126938D02*
G02X512050Y129402I2464J0D01*
G01X510886Y115002D02*
Y126938D01*
G01X509586Y114463D02*
Y126938D01*
G01X520862Y105026D02*
X510886Y115002D01*
G01X526970Y97079D02*
X509586Y114463D01*
G01X524186Y101702D02*
X523019Y102869D01*
G01X526970Y97079D02*
X509586Y114463D01*
G01X527509Y98379D02*
X526342Y99546D01*
G01X526970Y97079D02*
X509586Y114463D01*
G01X570091Y98379D02*
X527509D01*
G01X570630Y97079D02*
X526970D01*
G01X512050Y129402D02*
X512929D01*
G01X512050Y128102D02*
X512929D01*
G01X509586Y126938D02*
G02X512050Y129402I2464J0D01*
G01X510886Y126938D02*
G02X512050Y128102I1164J0D01*
G01X509586Y114463D02*
Y126938D01*
G01X510886Y115002D02*
Y126938D01*
G01X526970Y97079D02*
X509586Y114463D01*
G01X520862Y105026D02*
X510886Y115002D01*
G01X524186Y101702D02*
X523019Y102869D01*
G01X527509Y98379D02*
X526342Y99546D01*
G01X570630Y97079D02*
X526970D01*
G01X570091Y98379D02*
X527509D01*
G01X519137Y132827D02*
X520016D01*
G01X517973Y131663D02*
G02X519137Y132827I1164J0D01*
G01X516673Y131663D02*
G02X519137Y134127I2464J0D01*
G01X517973Y116170D02*
Y131663D01*
G01X516673Y115631D02*
Y131663D01*
G01X532166Y101977D02*
X517973Y116170D01*
G01X531627Y100677D02*
X516673Y115631D01*
G01X569073Y101977D02*
X532166D01*
G01X569612Y100677D02*
X531627D01*
G01X519137Y132827D02*
X520016D01*
G01X516673Y131663D02*
G02X519137Y134127I2464J0D01*
G01X517973Y131663D02*
G02X519137Y132827I1164J0D01*
G01X516673Y115631D02*
Y131663D01*
G01X517973Y116170D02*
Y131663D01*
G01X531627Y100677D02*
X516673Y115631D01*
G01X532166Y101977D02*
X517973Y116170D01*
G01X569612Y100677D02*
X531627D01*
G01X569073Y101977D02*
X532166D01*
G01X526224Y128102D02*
X527103D01*
G01X526224Y129402D02*
X527103D01*
G01X525060Y126938D02*
G02X526224Y128102I1164J0D01*
G01X523760Y126938D02*
G02X526224Y129402I2464J0D01*
G01X525060Y114518D02*
Y126938D01*
G01X523760Y113979D02*
Y126938D01*
G01X534243Y105335D02*
X525060Y114518D01*
G01X533704Y104035D02*
X523760Y113979D01*
G01X567873Y105335D02*
X534243D01*
G01X568412Y104035D02*
X533704D01*
G01X526224Y129402D02*
X527103D01*
G01X526224Y128102D02*
X527103D01*
G01X523760Y126938D02*
G02X526224Y129402I2464J0D01*
G01X525060Y126938D02*
G02X526224Y128102I1164J0D01*
G01X523760Y113979D02*
Y126938D01*
G01X525060Y114518D02*
Y126938D01*
G01X533704Y104035D02*
X523760Y113979D01*
G01X534243Y105335D02*
X525060Y114518D01*
G01X568412Y104035D02*
X533704D01*
G01X567873Y105335D02*
X534243D01*
G01X532146Y116148D02*
X539360Y108934D01*
G01X538821Y107634D02*
X530846Y115609D01*
G01X532146Y131663D02*
Y116148D01*
G01X530846Y115609D02*
Y131663D01*
G01X533310Y132827D02*
G03X532146Y131663I0J-1164D01*
G01X530846D02*
G02X533310Y134127I2464J0D01*
G01X534189Y132827D02*
X533310D01*
G01X534189D02*
X533310D01*
G01X530846Y131663D02*
G02X533310Y134127I2464J0D01*
G01Y132827D02*
G03X532146Y131663I0J-1164D01*
G01X530846Y115609D02*
Y131663D01*
G01X532146D02*
Y116148D01*
G01X538821Y107634D02*
X530846Y115609D01*
G01X532146Y116148D02*
X539360Y108934D01*
G01X505843Y134127D02*
X504964D01*
G01X505843D02*
X504964D01*
G01X519137D02*
X520016D01*
G01X519137D02*
X520016D01*
G01X533310D02*
X534189D01*
G01X533310D02*
X534189D01*
G01X547450Y132815D02*
X548300D01*
G01X546319Y131684D02*
G02X547450Y132815I1131J0D01*
G01X545019Y131684D02*
G02X547450Y134115I2431J0D01*
G01X546319Y121783D02*
Y131684D01*
G01X545019Y121244D02*
Y131684D01*
G01X552810Y115292D02*
X546319Y121783D01*
G01X552271Y113992D02*
X545019Y121244D01*
G01X563435Y115292D02*
X552810D01*
G01X563974Y113992D02*
X552271D01*
G01X567843Y119699D02*
X563435Y115292D01*
G01X568856Y118872D02*
X563974Y113992D01*
G01X576719Y133135D02*
X567843Y119699D01*
G01X577945Y132630D02*
X568856Y118872D01*
G01X577117Y135123D02*
X576719Y133135D01*
G01X596460Y225198D02*
X577945Y132630D01*
G01X596460Y225198D02*
X577945Y132630D01*
G01X596460Y225198D02*
X577945Y132630D01*
G01X596460Y225198D02*
X577945Y132630D01*
G01X596460Y225198D02*
X577945Y132630D01*
G01X596460Y225198D02*
X577945Y132630D01*
G01X596460Y225198D02*
X577945Y132630D01*
G01X596460Y225198D02*
X577945Y132630D01*
G01X596460Y225198D02*
X577945Y132630D01*
G01X547450Y132815D02*
X548300D01*
G01X545019Y131684D02*
G02X547450Y134115I2431J0D01*
G01X546319Y131684D02*
G02X547450Y132815I1131J0D01*
G01X545019Y121244D02*
Y131684D01*
G01X546319Y121783D02*
Y131684D01*
G01X552271Y113992D02*
X545019Y121244D01*
G01X552810Y115292D02*
X546319Y121783D01*
G01X563974Y113992D02*
X552271D01*
G01X563435Y115292D02*
X552810D01*
G01X568856Y118872D02*
X563974Y113992D01*
G01X567843Y119699D02*
X563435Y115292D01*
G01X577945Y132630D02*
X568856Y118872D01*
G01X576719Y133135D02*
X567843Y119699D01*
G01X596460Y225198D02*
X577945Y132630D01*
G01X577117Y135123D02*
X576719Y133135D01*
G01X554537Y128091D02*
X555387D01*
G01X554537Y129391D02*
X555387D01*
G01X553406Y126960D02*
G02X554537Y128091I1131J0D01*
G01X552106Y126960D02*
G02X554537Y129391I2431J0D01*
G01X553406Y119894D02*
Y126960D01*
G01X552106Y119355D02*
Y126960D01*
G01X554949Y118351D02*
X553406Y119894D01*
G01X554410Y117051D02*
X552106Y119355D01*
G01X561635Y118351D02*
X554949D01*
G01X562174Y117051D02*
X554410D01*
G01X565532Y122248D02*
X561635Y118351D01*
G01X566543Y121419D02*
X562174Y117051D01*
G01X572715Y133021D02*
X565532Y122248D01*
G01X573942Y132517D02*
X566543Y121419D01*
G01X573030Y134641D02*
X572715Y133021D01*
G01X592372Y227337D02*
X573942Y132517D01*
G01X592372Y227337D02*
X573942Y132517D01*
G01X592372Y227337D02*
X573942Y132517D01*
G01X592372Y227337D02*
X573942Y132517D01*
G01X592372Y227337D02*
X573942Y132517D01*
G01X592372Y227337D02*
X573942Y132517D01*
G01X592372Y227337D02*
X573942Y132517D01*
G01X592372Y227337D02*
X573942Y132517D01*
G01X592372Y227337D02*
X573942Y132517D01*
G01X554537Y129391D02*
X555387D01*
G01X554537Y128091D02*
X555387D01*
G01X552106Y126960D02*
G02X554537Y129391I2431J0D01*
G01X553406Y126960D02*
G02X554537Y128091I1131J0D01*
G01X552106Y119355D02*
Y126960D01*
G01X553406Y119894D02*
Y126960D01*
G01X554410Y117051D02*
X552106Y119355D01*
G01X554949Y118351D02*
X553406Y119894D01*
G01X562174Y117051D02*
X554410D01*
G01X561635Y118351D02*
X554949D01*
G01X566543Y121419D02*
X562174Y117051D01*
G01X565532Y122248D02*
X561635Y118351D01*
G01X573942Y132517D02*
X566543Y121419D01*
G01X572715Y133021D02*
X565532Y122248D01*
G01X592372Y227337D02*
X573942Y132517D01*
G01X573030Y134641D02*
X572715Y133021D01*
G01X540397Y128102D02*
X541276D01*
G01X540397Y129402D02*
X541276D01*
G01X539233Y126938D02*
G02X540397Y128102I1164J0D01*
G01X537933Y126938D02*
G02X540397Y129402I2464J0D01*
G01X539233Y120455D02*
Y126938D01*
G01X537933Y119916D02*
Y126938D01*
G01X547574Y112114D02*
X539233Y120455D01*
G01X547035Y110814D02*
X537933Y119916D01*
G01X565186Y112114D02*
X547574D01*
G01X565725Y110814D02*
X547035D01*
G01X569646Y116574D02*
X565186Y112114D01*
G01X570657Y115745D02*
X565725Y110814D01*
G01X581229Y133948D02*
X569646Y116574D01*
G01X582454Y133440D02*
X570657Y115745D01*
G01X600436Y223349D02*
X582454Y133440D01*
G01X600436Y223349D02*
X582454Y133440D01*
G01X600436Y223349D02*
X582454Y133440D01*
G01X600436Y223349D02*
X582454Y133440D01*
G01X600436Y223349D02*
X582454Y133440D01*
G01X600436Y223349D02*
X582454Y133440D01*
G01X600436Y223349D02*
X582454Y133440D01*
G01X600436Y223349D02*
X582454Y133440D01*
G01X600436Y223349D02*
X582454Y133440D01*
G01X540397Y129402D02*
X541276D01*
G01X540397Y128102D02*
X541276D01*
G01X537933Y126938D02*
G02X540397Y129402I2464J0D01*
G01X539233Y126938D02*
G02X540397Y128102I1164J0D01*
G01X537933Y119916D02*
Y126938D01*
G01X539233Y120455D02*
Y126938D01*
G01X547035Y110814D02*
X537933Y119916D01*
G01X547574Y112114D02*
X539233Y120455D01*
G01X565725Y110814D02*
X547035D01*
G01X565186Y112114D02*
X547574D01*
G01X570657Y115745D02*
X565725Y110814D01*
G01X569646Y116574D02*
X565186Y112114D01*
G01X582454Y133440D02*
X570657Y115745D01*
G01X581229Y133948D02*
X569646Y116574D01*
G01X600436Y223349D02*
X582454Y133440D01*
G01X583436Y107186D02*
X571330Y95080D01*
G01X571869Y93780D02*
X584447Y106357D01*
G01X601628Y134475D02*
X583436Y107186D01*
G01X584447Y106357D02*
X602853Y133967D01*
G01X584447Y106357D02*
X602853Y133967D01*
G01X601628Y134475D02*
X583436Y107186D01*
G01X571869Y93780D02*
X584447Y106357D01*
G01X583436Y107186D02*
X571330Y95080D01*
G01X581149Y109437D02*
X570091Y98379D01*
G01X582160Y108608D02*
X570630Y97079D01*
G01X597691Y134248D02*
X581149Y109437D01*
G01X598916Y133740D02*
X582160Y108608D01*
G01X615471Y216527D02*
X598916Y133740D01*
G01X615471Y216527D02*
X598916Y133740D01*
G01X615471Y216527D02*
X598916Y133740D01*
G01X615471Y216527D02*
X598916Y133740D01*
G01X615471Y216527D02*
X598916Y133740D01*
G01X615471Y216527D02*
X598916Y133740D01*
G01X615471Y216527D02*
X598916Y133740D01*
G01X615471Y216527D02*
X598916Y133740D01*
G01X615471Y216527D02*
X598916Y133740D01*
G01X582160Y108608D02*
X570630Y97079D01*
G01X581149Y109437D02*
X570091Y98379D01*
G01X598916Y133740D02*
X582160Y108608D01*
G01X597691Y134248D02*
X581149Y109437D01*
G01X615471Y216527D02*
X598916Y133740D01*
G01X578915Y111819D02*
X569073Y101977D01*
G01X579926Y110990D02*
X569612Y100677D01*
G01X593671Y133953D02*
X578915Y111819D01*
G01X594896Y133445D02*
X579926Y110990D01*
G01X611885Y218398D02*
X594896Y133445D01*
G01X611885Y218398D02*
X594896Y133445D01*
G01X611885Y218398D02*
X594896Y133445D01*
G01X611885Y218398D02*
X594896Y133445D01*
G01X611885Y218398D02*
X594896Y133445D01*
G01X611885Y218398D02*
X594896Y133445D01*
G01X611885Y218398D02*
X594896Y133445D01*
G01X611885Y218398D02*
X594896Y133445D01*
G01X611885Y218398D02*
X594896Y133445D01*
G01X579926Y110990D02*
X569612Y100677D01*
G01X578915Y111819D02*
X569073Y101977D01*
G01X594896Y133445D02*
X579926Y110990D01*
G01X593671Y133953D02*
X578915Y111819D01*
G01X611885Y218398D02*
X594896Y133445D01*
G01X574855Y112317D02*
X567873Y105335D01*
G01X575866Y111488D02*
X568412Y104035D01*
G01X589730Y134630D02*
X574855Y112317D01*
G01X583374Y122751D02*
X575866Y111488D01*
G01X590955Y134122D02*
X583374Y122752D01*
G01X575866Y111488D02*
X568412Y104035D01*
G01X574855Y112317D02*
X567873Y105335D01*
G01X583374Y122751D02*
X575866Y111488D01*
G01X589730Y134630D02*
X574855Y112317D01*
G01X590955Y134122D02*
X583374Y122752D01*
G01X589730Y134630D02*
X574855Y112317D01*
G01X572738Y115247D02*
X585725Y134726D01*
G01X586950Y134218D02*
X573749Y114418D01*
G01X566425Y108934D02*
X572738Y115247D01*
G01X573749Y114418D02*
X566964Y107634D01*
G01X539360Y108934D02*
X566425D01*
G01X566964Y107634D02*
X538821D01*
G01X566964D02*
X538821D01*
G01X539360Y108934D02*
X566425D01*
G01X573749Y114418D02*
X566964Y107634D01*
G01X566425Y108934D02*
X572738Y115247D01*
G01X586950Y134218D02*
X573749Y114418D01*
G01X572738Y115247D02*
X585725Y134726D01*
G01X577539Y186835D02*
X585535Y223041D01*
G01X580265Y205213D02*
X576321Y187350D01*
G01X571021Y176946D02*
X577539Y186835D01*
G01X576321Y187350D02*
X570044Y177828D01*
G01X563260Y170599D02*
X571021Y176946D01*
G01X570044Y177828D02*
X562796Y171899D01*
G01X557149Y170599D02*
X563260D01*
G01X562796Y171899D02*
X557149D01*
G01X562796D02*
X557149D01*
G01Y170599D02*
X563260D01*
G01X570044Y177828D02*
X562796Y171899D01*
G01X563260Y170599D02*
X571021Y176946D01*
G01X576321Y187350D02*
X570044Y177828D01*
G01X571021Y176946D02*
X577539Y186835D01*
G01X580265Y205213D02*
X576321Y187350D01*
G01X577539Y186835D02*
X585535Y223041D01*
G01X577539Y186835D02*
X585535Y223041D01*
G01X547450Y134115D02*
X548300D01*
G01X578039Y139732D02*
X577715Y138114D01*
G01X578961Y144341D02*
X578637Y142723D01*
G01X579882Y148949D02*
X579559Y147331D01*
G01X590622Y202642D02*
X580481Y151940D01*
G01X547450Y134115D02*
X548300D01*
G01X578039Y139732D02*
X577715Y138114D01*
G01X578961Y144341D02*
X578637Y142723D01*
G01X579882Y148949D02*
X579559Y147331D01*
G01X590622Y202642D02*
X580481Y151940D01*
G01X573927Y139254D02*
X573612Y137635D01*
G01X574823Y143868D02*
X574508Y142248D01*
G01X575720Y148482D02*
X575405Y146862D01*
G01X587459Y208878D02*
X576302Y151476D01*
G01X573927Y139254D02*
X573612Y137635D01*
G01X574823Y143868D02*
X574508Y142248D01*
G01X575720Y148482D02*
X575405Y146862D01*
G01X587459Y208878D02*
X576302Y151476D01*
G01X581553Y135566D02*
X581229Y133948D01*
G01X582474Y140175D02*
X582151Y138557D01*
G01X583396Y144783D02*
X583073Y143165D01*
G01X584318Y149392D02*
X583994Y147774D01*
G01X595423Y204914D02*
X584916Y152383D01*
G01X581553Y135566D02*
X581229Y133948D01*
G01X582474Y140175D02*
X582151Y138557D01*
G01X583396Y144783D02*
X583073Y143165D01*
G01X584318Y149392D02*
X583994Y147774D01*
G01X595423Y204914D02*
X584916Y152383D01*
G01X601952Y136093D02*
X601628Y134475D01*
G01X601952Y136093D02*
X601628Y134475D01*
G01X598015Y135866D02*
X597691Y134248D01*
G01X598936Y140475D02*
X598613Y138857D01*
G01X599858Y145083D02*
X599534Y143465D01*
G01X600780Y149692D02*
X600456Y148074D01*
G01X610100Y196298D02*
X601378Y152683D01*
G01X598015Y135866D02*
X597691Y134248D01*
G01X598936Y140475D02*
X598613Y138857D01*
G01X599858Y145083D02*
X599534Y143465D01*
G01X600780Y149692D02*
X600456Y148074D01*
G01X610100Y196298D02*
X601378Y152683D01*
G01X593995Y135571D02*
X593671Y133953D01*
G01X594916Y140180D02*
X594593Y138562D01*
G01X595838Y144788D02*
X595514Y143170D01*
G01X596760Y149397D02*
X596436Y147779D01*
G01X606872Y199963D02*
X597358Y152388D01*
G01X593995Y135571D02*
X593671Y133953D01*
G01X594916Y140180D02*
X594593Y138562D01*
G01X595838Y144788D02*
X595514Y143170D01*
G01X596760Y149397D02*
X596436Y147779D01*
G01X606872Y199963D02*
X597358Y152388D01*
G01X590054Y136248D02*
X589730Y134630D01*
G01X608068Y219674D02*
X590955Y134122D01*
G01X590976Y140857D02*
X590652Y139239D01*
G01X608068Y219674D02*
X590955Y134122D01*
G01X591897Y145465D02*
X591574Y143847D01*
G01X608068Y219674D02*
X590955Y134122D01*
G01X592819Y150074D02*
X592496Y148456D01*
G01X608068Y219674D02*
X590955Y134122D01*
G01X603054Y201239D02*
X593418Y153065D01*
G01X608068Y219674D02*
X590955Y134122D01*
G01X608068Y219674D02*
X590955Y134122D01*
G01X608068Y219674D02*
X590955Y134122D01*
G01X608068Y219674D02*
X590955Y134122D01*
G01X608068Y219674D02*
X590955Y134122D01*
G01X608068Y219674D02*
X590955Y134122D01*
G01X590054Y136248D02*
X589730Y134630D01*
G01X590976Y140857D02*
X590652Y139239D01*
G01X591897Y145465D02*
X591574Y143847D01*
G01X592819Y150074D02*
X592496Y148456D01*
G01X603054Y201239D02*
X593418Y153065D01*
G01X604324Y221091D02*
X586950Y134218D01*
G01X604324Y221091D02*
X586950Y134218D01*
G01X604324Y221091D02*
X586950Y134218D01*
G01X604324Y221091D02*
X586950Y134218D01*
G01X589412Y153161D02*
X599311Y202656D01*
G01X604324Y221091D02*
X586950Y134218D01*
G01X588490Y148552D02*
X588814Y150170D01*
G01X604324Y221091D02*
X586950Y134218D01*
G01X587569Y143943D02*
X587892Y145561D01*
G01X604324Y221091D02*
X586950Y134218D01*
G01X586647Y139335D02*
X586970Y140953D01*
G01X604324Y221091D02*
X586950Y134218D01*
G01X585725Y134726D02*
X586049Y136344D01*
G01X604324Y221091D02*
X586950Y134218D01*
G01X604324Y221091D02*
X586950Y134218D01*
G01X589412Y153161D02*
X599311Y202656D01*
G01X588490Y148552D02*
X588814Y150170D01*
G01X587569Y143943D02*
X587892Y145561D01*
G01X586647Y139335D02*
X586970Y140953D01*
G01X585725Y134726D02*
X586049Y136344D01*
G01X589679Y300370D02*
X579829Y249462D01*
G01X581150Y249444D02*
X586026Y274645D01*
G01X589679Y300370D02*
X579829Y249462D01*
G01X585535Y223041D02*
X581150Y249444D01*
G01X579829Y249462D02*
X584211Y223076D01*
G01X584210D02*
X580265Y205213D01*
G01X584210Y223076D02*
X580265Y205213D01*
G01X579829Y249462D02*
X584211Y223076D01*
G01X585535Y223041D02*
X581150Y249444D01*
G01X589679Y300370D02*
X579829Y249462D01*
G01X581150Y249444D02*
X586026Y274645D01*
G01X591544Y207251D02*
X591221Y205633D01*
G01X592466Y211859D02*
X592142Y210241D01*
G01X593388Y216468D02*
X593064Y214850D01*
G01X595134Y225198D02*
X593986Y219459D01*
G01X590314Y249312D02*
X595134Y225198D01*
G01X591640Y249312D02*
X596460Y225198D01*
G01X599847Y296958D02*
X590314Y249312D01*
G01X601072Y296450D02*
X591640Y249312D01*
G01X591544Y207251D02*
X591221Y205633D01*
G01X592466Y211859D02*
X592142Y210241D01*
G01X593388Y216468D02*
X593064Y214850D01*
G01X595134Y225198D02*
X593986Y219459D01*
G01X591640Y249312D02*
X596460Y225198D01*
G01X590314Y249312D02*
X595134Y225198D01*
G01X601072Y296450D02*
X591640Y249312D01*
G01X599847Y296958D02*
X590314Y249312D01*
G01X588356Y213492D02*
X588041Y211872D01*
G01X589253Y218106D02*
X588938Y216486D01*
G01X590149Y222719D02*
X589834Y221100D01*
G01X591046Y227333D02*
X590731Y225713D01*
G01X586427Y250433D02*
X591046Y227333D01*
G01X587753Y250433D02*
X592372Y227337D01*
G01X595971Y298189D02*
X586427Y250433D01*
G01X597195Y297678D02*
X587753Y250433D01*
G01X588356Y213492D02*
X588041Y211872D01*
G01X589253Y218106D02*
X588938Y216486D01*
G01X590149Y222719D02*
X589834Y221100D01*
G01X591046Y227333D02*
X590731Y225713D01*
G01X587753Y250433D02*
X592372Y227337D01*
G01X586427Y250433D02*
X591046Y227333D01*
G01X597195Y297678D02*
X587753Y250433D01*
G01X595971Y298189D02*
X586427Y250433D01*
G01X596345Y209523D02*
X596021Y207905D01*
G01X597266Y214132D02*
X596943Y212514D01*
G01X598188Y218740D02*
X597865Y217122D01*
G01X599110Y223349D02*
X598786Y221731D01*
G01X593845Y249668D02*
X599110Y223349D01*
G01X595171Y249668D02*
X600436Y223349D01*
G01X602922Y295033D02*
X593845Y249668D01*
G01X604147Y294525D02*
X595171Y249668D01*
G01X596345Y209523D02*
X596021Y207905D01*
G01X597266Y214132D02*
X596943Y212514D01*
G01X598188Y218740D02*
X597865Y217122D01*
G01X599110Y223349D02*
X598786Y221731D01*
G01X595171Y249668D02*
X600436Y223349D01*
G01X593845Y249668D02*
X599110Y223349D01*
G01X604147Y294525D02*
X595171Y249668D01*
G01X602922Y295033D02*
X593845Y249668D01*
G01X600849Y249136D02*
X606742Y219674D01*
G01X602175Y249136D02*
X608068Y219674D01*
G01X609201Y290917D02*
X600849Y249136D01*
G01X610426Y290410D02*
X602175Y249136D01*
G01D02*
X608068Y219674D01*
G01X600849Y249136D02*
X606742Y219674D01*
G01X610426Y290410D02*
X602175Y249136D01*
G01X609201Y290917D02*
X600849Y249136D01*
G01X597266Y249754D02*
X605742Y292146D01*
G01X606967Y291639D02*
X598592Y249754D01*
G01X602998Y221091D02*
X597266Y249754D01*
G01X598592D02*
X604324Y221091D01*
G01X601753Y214864D02*
X602076Y216482D01*
G01X600831Y210256D02*
X601154Y211874D01*
G01X599909Y205647D02*
X600233Y207265D01*
G01X601753Y214864D02*
X602076Y216482D01*
G01X600831Y210256D02*
X601154Y211874D01*
G01X599909Y205647D02*
X600233Y207265D01*
G01X598592Y249754D02*
X604324Y221091D01*
G01X602998D02*
X597266Y249754D01*
G01X606967Y291639D02*
X598592Y249754D01*
G01X597266D02*
X605742Y292146D01*
G01X590901Y299842D02*
X607025Y322215D01*
G01X606117Y323181D02*
X589679Y300370D01*
G01X586027Y274645D02*
X590901Y299842D01*
G01X586027Y274645D02*
X590901Y299842D01*
G01X606117Y323181D02*
X589679Y300370D01*
G01X590901Y299842D02*
X607025Y322215D01*
G01X613291Y317116D02*
X599847Y296958D01*
G01X614229Y316178D02*
X601072Y296450D01*
G01X614229Y316178D02*
X601072Y296450D01*
G01X613291Y317116D02*
X599847Y296958D01*
G01X609960Y318928D02*
X595971Y298189D01*
G01X610897Y317991D02*
X597195Y297678D01*
G01X610897Y317991D02*
X597195Y297678D01*
G01X609960Y318928D02*
X595971Y298189D01*
G01X602853Y133967D02*
X618989Y214647D01*
G01X602873Y140702D02*
X602550Y139084D01*
G01X602853Y133967D02*
X618989Y214647D01*
G01X603795Y145310D02*
X603472Y143692D01*
G01X602853Y133967D02*
X618989Y214647D01*
G01X604717Y149919D02*
X604393Y148301D01*
G01X602853Y133967D02*
X618989Y214647D01*
G01X613976Y196212D02*
X605315Y152910D01*
G01X602853Y133967D02*
X618989Y214647D01*
G01X614898Y200821D02*
X614574Y199203D01*
G01X602853Y133967D02*
X618989Y214647D01*
G01X602853Y133967D02*
X618989Y214647D01*
G01X602853Y133967D02*
X618989Y214647D01*
G01X602853Y133967D02*
X618989Y214647D01*
G01X602853Y133967D02*
X618989Y214647D01*
G01X602873Y140702D02*
X602550Y139084D01*
G01X603795Y145310D02*
X603472Y143692D01*
G01X604717Y149919D02*
X604393Y148301D01*
G01X613976Y196212D02*
X605315Y152910D01*
G01X614898Y200821D02*
X614574Y199203D01*
G01X611022Y200907D02*
X610698Y199289D01*
G01X611022Y200907D02*
X610698Y199289D01*
G01X615819Y205430D02*
X615496Y203812D01*
G01X616741Y210038D02*
X616418Y208420D01*
G01X617663Y214647D02*
X617339Y213029D01*
G01X611514Y245396D02*
X617663Y214647D01*
G01X618989D02*
X612840Y245396D01*
G01X611564Y245650D02*
X611514Y245396D01*
G01X612840D02*
X620786Y285131D01*
G01X619561Y285638D02*
X611565Y245650D01*
G01X612840Y245396D02*
X620786Y285131D01*
G01X612840Y245396D02*
X620786Y285131D01*
G01X611564Y245650D02*
X611514Y245396D01*
G01X619561Y285638D02*
X611565Y245650D01*
G01X618989Y214647D02*
X612840Y245396D01*
G01X611514D02*
X617663Y214647D01*
G01X615819Y205430D02*
X615496Y203812D01*
G01X616741Y210038D02*
X616418Y208420D01*
G01X617663Y214647D02*
X617339Y213029D01*
G01X611943Y205516D02*
X611620Y203898D01*
G01X612865Y210124D02*
X612541Y208506D01*
G01X614145Y216527D02*
X613463Y213115D01*
G01X608256Y245978D02*
X614145Y216527D01*
G01X609581Y245985D02*
X615471Y216527D01*
G01X615997Y286876D02*
X608256Y245978D01*
G01X617226Y286374D02*
X609581Y245985D01*
G01X611943Y205516D02*
X611620Y203898D01*
G01X612865Y210124D02*
X612541Y208506D01*
G01X614145Y216527D02*
X613463Y213115D01*
G01X609581Y245985D02*
X615471Y216527D01*
G01X608256Y245978D02*
X614145Y216527D01*
G01X617226Y286374D02*
X609581Y245985D01*
G01X615997Y286876D02*
X608256Y245978D01*
G01X607794Y204572D02*
X607470Y202954D01*
G01X608716Y209181D02*
X608392Y207563D01*
G01X609637Y213789D02*
X609314Y212171D01*
G01X610559Y218398D02*
X610235Y216780D01*
G01X604505Y248665D02*
X610559Y218398D01*
G01X605831Y248665D02*
X611885Y218398D01*
G01X612599Y289124D02*
X604505Y248665D01*
G01X613824Y288616D02*
X605831Y248665D01*
G01X607794Y204572D02*
X607470Y202954D01*
G01X608716Y209181D02*
X608392Y207563D01*
G01X609637Y213789D02*
X609314Y212171D01*
G01X610559Y218398D02*
X610235Y216780D01*
G01X605831Y248665D02*
X611885Y218398D01*
G01X604505Y248665D02*
X610559Y218398D01*
G01X613824Y288616D02*
X605831Y248665D01*
G01X612599Y289124D02*
X604505Y248665D01*
G01X603976Y205848D02*
X603653Y204230D01*
G01X604898Y210457D02*
X604575Y208839D01*
G01X605820Y215065D02*
X605496Y213447D01*
G01X606742Y219674D02*
X606418Y218056D01*
G01X603976Y205848D02*
X603653Y204230D01*
G01X604898Y210457D02*
X604575Y208839D01*
G01X605820Y215065D02*
X605496Y213447D01*
G01X606742Y219674D02*
X606418Y218056D01*
G01X602674Y219473D02*
X602998Y221091D01*
G01X602674Y219473D02*
X602998Y221091D01*
G01X607025Y322215D02*
X623561Y332631D01*
G01X622556Y333536D02*
X606117Y323181D01*
G01X622556Y333536D02*
X606117Y323181D01*
G01X607025Y322215D02*
X623561Y332631D01*
G01X684795Y364785D02*
X613291Y317116D01*
G01X685300Y363558D02*
X614229Y316178D01*
G01X685300Y363558D02*
X614229Y316178D01*
G01X684795Y364785D02*
X613291Y317116D01*
G01X632204Y333932D02*
X609960Y318928D01*
G01X682909Y366563D02*
X610897Y317991D01*
G01X682909Y366563D02*
X610897Y317991D01*
G01X682909Y366563D02*
X610897Y317991D01*
G01X682909Y366563D02*
X610897Y317991D01*
G01X682909Y366563D02*
X610897Y317991D01*
G01X682909Y366563D02*
X610897Y317991D01*
G01X632204Y333932D02*
X609960Y318928D01*
G01X616268Y315010D02*
X602922Y295033D01*
G01X617205Y314072D02*
X604147Y294525D01*
G01X664340Y347059D02*
X616268Y315010D01*
G01X664845Y345832D02*
X617205Y314072D01*
G01D02*
X604147Y294525D01*
G01X616268Y315010D02*
X602922Y295033D01*
G01X664845Y345832D02*
X617205Y314072D01*
G01X664340Y347059D02*
X616268Y315010D01*
G01X631656Y303783D02*
X619561Y285638D01*
G01X620786Y285131D02*
X632594Y302845D01*
G01X672401Y330947D02*
X631656Y303783D01*
G01X632594Y302845D02*
X672909Y329722D01*
G01X632594Y302845D02*
X672909Y329722D01*
G01X672401Y330947D02*
X631656Y303783D01*
G01X620786Y285131D02*
X632594Y302845D01*
G01X631656Y303783D02*
X619561Y285638D01*
G01X629176Y306644D02*
X615997Y286876D01*
G01X623669Y296040D02*
X617226Y286374D01*
G01X630114Y305706D02*
X623670Y296040D01*
G01X670622Y334274D02*
X629176Y306644D01*
G01X671129Y333049D02*
X630114Y305706D01*
G01X623669Y296040D02*
X617226Y286374D01*
G01X629176Y306644D02*
X615997Y286876D01*
G01X630114Y305706D02*
X623670Y296040D01*
G01X629176Y306644D02*
X615997Y286876D01*
G01X671129Y333049D02*
X630114Y305706D01*
G01X670622Y334274D02*
X629176Y306644D01*
G01X625398Y308320D02*
X612599Y289124D01*
G01X620079Y297999D02*
X613824Y288616D01*
G01X626336Y307382D02*
X620080Y297999D01*
G01X668868Y337299D02*
X625398Y308320D01*
G01X669373Y336073D02*
X626336Y307382D01*
G01X620079Y297999D02*
X613824Y288616D01*
G01X625398Y308320D02*
X612599Y289124D01*
G01X626336Y307382D02*
X620080Y297999D01*
G01X625398Y308320D02*
X612599Y289124D01*
G01X669373Y336073D02*
X626336Y307382D01*
G01X668868Y337299D02*
X625398Y308320D01*
G01X621806Y309824D02*
X609201Y290917D01*
G01X622744Y308886D02*
X610426Y290410D01*
G01X667946Y340585D02*
X621806Y309824D01*
G01X668450Y339358D02*
X622744Y308886D01*
G01D02*
X610426Y290410D01*
G01X621806Y309824D02*
X609201Y290917D01*
G01X668450Y339358D02*
X622744Y308886D01*
G01X667946Y340585D02*
X621806Y309824D01*
G01X619391Y312623D02*
X666073Y343742D01*
G01X666577Y342515D02*
X620329Y311685D01*
G01X605742Y292146D02*
X619391Y312623D01*
G01X620329Y311685D02*
X606967Y291639D01*
G01X620329Y311685D02*
X606967Y291639D01*
G01X605742Y292146D02*
X619391Y312623D01*
G01X666577Y342515D02*
X620329Y311685D01*
G01X619391Y312623D02*
X666073Y343742D01*
G01X648890Y350228D02*
X679692Y371125D01*
G01X663562Y361754D02*
X648335Y351423D01*
G01X671262Y366977D02*
X663562Y361754D01*
G01X636474Y346743D02*
X648890Y350228D01*
G01X648335Y351423D02*
X635952Y347947D01*
G01X627972Y341600D02*
X636474Y346743D01*
G01X635952Y347947D02*
X626973Y342516D01*
G01X623561Y332631D02*
X627972Y341600D01*
G01X626973Y342516D02*
X622556Y333536D01*
G01X626973Y342516D02*
X622556Y333536D01*
G01X623561Y332631D02*
X627972Y341600D01*
G01X635952Y347947D02*
X626973Y342516D01*
G01X627972Y341600D02*
X636474Y346743D01*
G01X648335Y351423D02*
X635952Y347947D01*
G01X636474Y346743D02*
X648890Y350228D01*
G01X663562Y361754D02*
X648335Y351423D01*
G01X648890Y350228D02*
X679692Y371125D01*
G01X671262Y366977D02*
X663562Y361754D01*
G01X648890Y350228D02*
X679692Y371125D01*
G01X648890Y350228D02*
X679692Y371125D01*
G01X634733Y335637D02*
X633761Y335826D01*
G01X636100Y336559D02*
X634733Y335637D01*
G01X638629Y338265D02*
X637657Y338454D01*
G01X682401Y367789D02*
X638629Y338265D01*
G01X634733Y335637D02*
X633761Y335826D01*
G01X636100Y336559D02*
X634733Y335637D01*
G01X638629Y338265D02*
X637657Y338454D01*
G01X682401Y367789D02*
X638629Y338265D01*
G01X668573Y347882D02*
X664340Y347059D01*
G01X669081Y346655D02*
X664845Y345832D01*
G01X669081Y346655D02*
X664845Y345832D01*
G01X668573Y347882D02*
X664340Y347059D01*
G01X679333Y342798D02*
X667946Y340585D01*
G01X679333Y342798D02*
X667946Y340585D01*
G01X673963Y343951D02*
X666577Y342515D01*
G01X666073Y343742D02*
X669765Y344460D01*
G01X673963Y343951D02*
X666577Y342515D01*
G01X673963Y343951D02*
X666577Y342515D01*
G01X666073Y343742D02*
X669765Y344460D01*
G01X672909Y329722D02*
X732915Y341723D01*
G01X672909Y329722D02*
X732915Y341723D01*
G01X729382Y380589D02*
X798544Y367504D01*
G01X799037Y368734D02*
X729381Y381913D01*
G01X679692Y371125D02*
X729382Y380589D01*
G01X729369Y381910D02*
X679185Y372352D01*
G01D02*
X671262Y366977D01*
G01X679185Y372352D02*
X671262Y366977D01*
G01X729369Y381910D02*
X679185Y372352D01*
G01X679692Y371125D02*
X729382Y380589D01*
G01X799037Y368734D02*
X729381Y381913D01*
G01X729382Y380589D02*
X798544Y367504D01*
G01X728880Y373374D02*
X684795Y364785D01*
G01X728877Y372048D02*
X685300Y363558D01*
G01X777158Y363721D02*
X728880Y373374D01*
G01X776651Y362496D02*
X728877Y372048D01*
G01D02*
X685300Y363558D01*
G01X728880Y373374D02*
X684795Y364785D01*
G01X776651Y362496D02*
X728877Y372048D01*
G01X777158Y363721D02*
X728880Y373374D01*
G01X729485Y376942D02*
X682401Y367789D01*
G01X706195Y371090D02*
X682909Y366563D01*
G01X729481Y375616D02*
X706195Y371090D01*
G01X761399Y370560D02*
X729485Y376942D01*
G01X792804Y362955D02*
X729481Y375616D01*
G01X792804Y362955D02*
X729481Y375616D01*
G01X706195Y371090D02*
X682909Y366563D01*
G01X729485Y376942D02*
X682401Y367789D01*
G01X729481Y375616D02*
X706195Y371090D01*
G01X729485Y376942D02*
X682401Y367789D01*
G01X792804Y362955D02*
X729481Y375616D01*
G01X761399Y370560D02*
X729485Y376942D01*
G01X674394Y351807D02*
X668573Y347881D01*
G01X689400Y360361D02*
X669081Y346655D01*
G01X676923Y353513D02*
X675951Y353702D01*
G01X689400Y360361D02*
X669081Y346655D01*
G01X678290Y354436D02*
X676923Y353513D01*
G01X689400Y360361D02*
X669081Y346655D01*
G01X680819Y356141D02*
X679847Y356330D01*
G01X689400Y360361D02*
X669081Y346655D01*
G01X688891Y361586D02*
X680819Y356141D01*
G01X689400Y360361D02*
X669081Y346655D01*
G01X729185Y369542D02*
X688891Y361586D01*
G01X729183Y368216D02*
X689400Y360361D01*
G01X774775Y360423D02*
X729185Y369542D01*
G01X774268Y359198D02*
X729183Y368216D01*
G01X689400Y360361D02*
X669081Y346655D01*
G01X674394Y351807D02*
X668573Y347881D01*
G01X676923Y353513D02*
X675951Y353702D01*
G01X678290Y354436D02*
X676923Y353513D01*
G01X680819Y356141D02*
X679847Y356330D01*
G01X688891Y361586D02*
X680819Y356141D01*
G01X729183Y368216D02*
X689400Y360361D01*
G01X729185Y369542D02*
X688891Y361586D01*
G01X774268Y359198D02*
X729183Y368216D01*
G01X774775Y360423D02*
X729185Y369542D01*
G01X732915Y343049D02*
X672401Y330947D01*
G01X747010Y340229D02*
X732915Y343049D01*
G01Y341723D02*
X746369Y339031D01*
G01X732915Y341723D02*
X746369Y339031D01*
G01X747010Y340229D02*
X732915Y343049D01*
G01D02*
X672401Y330947D01*
G01X748285Y349800D02*
X670622Y334274D01*
G01X748414Y348500D02*
X671129Y333049D01*
G01X748414Y348500D02*
X671129Y333049D01*
G01X748285Y349800D02*
X670622Y334274D01*
G01X686812Y340829D02*
X668868Y337299D01*
G01X748056Y351550D02*
X669373Y336073D01*
G01X691424Y341736D02*
X689805Y341417D01*
G01X748056Y351550D02*
X669373Y336073D01*
G01X747929Y352850D02*
X694416Y342324D01*
G01X748056Y351550D02*
X669373Y336073D01*
G01X748056Y351550D02*
X669373Y336073D01*
G01X686812Y340829D02*
X668868Y337299D01*
G01X691424Y341736D02*
X689805Y341417D01*
G01X747929Y352850D02*
X694416Y342324D01*
G01X679841Y341572D02*
X668450Y339358D01*
G01X683348Y345506D02*
X679333Y342798D01*
G01X694492Y351455D02*
X679841Y341572D01*
G01X685876Y347212D02*
X684904Y347400D01*
G01X694492Y351455D02*
X679841Y341572D01*
G01X687244Y348134D02*
X685876Y347212D01*
G01X694492Y351455D02*
X679841Y341572D01*
G01X689773Y349840D02*
X688801Y350029D01*
G01X694492Y351455D02*
X679841Y341572D01*
G01X693983Y352680D02*
X689773Y349840D01*
G01X694492Y351455D02*
X679841Y341572D01*
G01X720474Y357901D02*
X693983Y352680D01*
G01X720472Y356575D02*
X694492Y351455D01*
G01X732950Y355405D02*
X720474Y357901D01*
G01X732950Y354079D02*
X720472Y356575D01*
G01X750215Y358858D02*
X732950Y355405D01*
G01X750215Y357532D02*
X732950Y354079D01*
G01X679841Y341572D02*
X668450Y339358D01*
G01X694492Y351455D02*
X679841Y341572D01*
G01X683348Y345506D02*
X679333Y342798D01*
G01X685876Y347212D02*
X684904Y347400D01*
G01X687244Y348134D02*
X685876Y347212D01*
G01X689773Y349840D02*
X688801Y350029D01*
G01X693983Y352680D02*
X689773Y349840D01*
G01X720472Y356575D02*
X694492Y351455D01*
G01X720474Y357901D02*
X693983Y352680D01*
G01X732950Y354079D02*
X720472Y356575D01*
G01X732950Y355405D02*
X720474Y357901D01*
G01X750215Y357532D02*
X732950Y354079D01*
G01X750215Y358858D02*
X732950Y355405D01*
G01X732948Y358806D02*
X749786Y362175D01*
G01Y360849D02*
X732948Y357480D01*
G01X720676Y361261D02*
X732948Y358806D01*
G01Y357480D02*
X720675Y359935D01*
G01X687581Y354705D02*
X720676Y361261D01*
G01X720675Y359935D02*
X688091Y353480D01*
G01X683413Y351894D02*
X687581Y354705D01*
G01X688091Y353480D02*
X673963Y343951D01*
G01X682441Y352083D02*
X683413Y351894D01*
G01X688091Y353480D02*
X673963Y343951D01*
G01X679517Y349266D02*
X680885Y350188D01*
G01X688091Y353480D02*
X673963Y343951D01*
G01X678545Y349454D02*
X679517Y349266D01*
G01X688091Y353480D02*
X673963Y343951D01*
G01X673455Y345177D02*
X676988Y347560D01*
G01X688091Y353480D02*
X673963Y343951D01*
G01X669765Y344461D02*
X673455Y345177D01*
G01X669765Y344461D02*
X673455Y345177D01*
G01X688091Y353480D02*
X673963Y343951D01*
G01X683413Y351894D02*
X687581Y354705D01*
G01X682441Y352083D02*
X683413Y351894D01*
G01X679517Y349266D02*
X680885Y350188D01*
G01X678545Y349454D02*
X679517Y349266D01*
G01X673455Y345177D02*
X676988Y347560D01*
G01X720675Y359935D02*
X688091Y353480D01*
G01X687581Y354705D02*
X720676Y361261D01*
G01X732948Y357480D02*
X720675Y359935D01*
G01X720676Y361261D02*
X732948Y358806D01*
G01X749786Y360849D02*
X732948Y357480D01*
G01Y358806D02*
X749786Y362175D01*
G01X798544Y367504D02*
X802428Y364988D01*
G01X803353Y365939D02*
X799044Y368729D01*
G01X803353Y365939D02*
X799044Y368729D01*
G01X798544Y367504D02*
X802428Y364988D01*
G01X780601Y361426D02*
X777158Y363721D01*
G01X787593Y355201D02*
X776651Y362496D01*
G01X781571Y361620D02*
X780601Y361426D01*
G01X787593Y355201D02*
X776651Y362496D01*
G01X784511Y358819D02*
X783138Y359734D01*
G01X787593Y355201D02*
X776651Y362496D01*
G01X785482Y359013D02*
X784511Y358819D01*
G01X787593Y355201D02*
X776651Y362496D01*
G01X788422Y356212D02*
X787049Y357127D01*
G01X787593Y355201D02*
X776651Y362496D01*
G01X788512Y356122D02*
X788422Y356212D01*
G01X796382Y346412D02*
X787593Y355201D01*
G01X797682Y346951D02*
X788512Y356121D01*
G01X796382Y346412D02*
X787593Y355201D01*
G01X797682Y341065D02*
Y346951D01*
G01X796382Y341604D02*
Y346412D01*
G01X794637Y338020D02*
X797682Y341065D01*
G01X795788Y341010D02*
X796382Y341604D01*
G01X795663Y340886D02*
X795788Y341010D01*
G01X793717Y338940D02*
X795663Y340886D01*
G01X787593Y355201D02*
X776651Y362496D01*
G01X780601Y361426D02*
X777158Y363721D01*
G01X781571Y361620D02*
X780601Y361426D01*
G01X784511Y358819D02*
X783138Y359734D01*
G01X785482Y359013D02*
X784511Y358819D01*
G01X788422Y356212D02*
X787049Y357127D01*
G01X796382Y346412D02*
X787593Y355201D01*
G01X788512Y356122D02*
X788422Y356212D01*
G01X797682Y346951D02*
X788512Y356121D01*
G01X796382Y341604D02*
Y346412D01*
G01X797682Y341065D02*
Y346951D01*
G01X795788Y341010D02*
X796382Y341604D01*
G01X794637Y338020D02*
X797682Y341065D01*
G01X795663Y340886D02*
X795788Y341010D01*
G01X794637Y338020D02*
X797682Y341065D01*
G01X793717Y338940D02*
X795663Y340886D01*
G01X794637Y338020D02*
X797682Y341065D01*
G01X793445Y364153D02*
X761399Y370560D01*
G01X806200Y351405D02*
X793445Y364153D01*
G01X804900Y350866D02*
X792804Y362955D01*
G01X793445Y364153D02*
X761399Y370560D01*
G01X804900Y350866D02*
X792804Y362955D01*
G01X806200Y351405D02*
X793445Y364153D01*
G01X782279Y355421D02*
X774775Y360423D01*
G01X781450Y354410D02*
X774268Y359198D01*
G01X783768Y353932D02*
X782279Y355421D01*
G01X782468Y353393D02*
X781450Y354410D01*
G01X783768Y350847D02*
Y353932D01*
G01X782468Y351386D02*
Y353393D01*
G01X783225Y350304D02*
X783768Y350847D01*
G01X781819Y350737D02*
X782468Y351386D01*
G01X783226Y350304D02*
X783225D01*
G01X781819Y350737D02*
X782468Y351386D01*
G01X782737Y349815D02*
X783226Y350304D01*
G01X781819Y350737D02*
X782468Y351386D01*
G01X781450Y354410D02*
X774268Y359198D01*
G01X782279Y355421D02*
X774775Y360423D01*
G01X782468Y353393D02*
X781450Y354410D01*
G01X783768Y353932D02*
X782279Y355421D01*
G01X782468Y351386D02*
Y353393D01*
G01X783768Y350847D02*
Y353932D01*
G01X781819Y350737D02*
X782468Y351386D01*
G01X783225Y350304D02*
X783768Y350847D01*
G01X783226Y350304D02*
X783225D01*
G01X782737Y349815D02*
X783226Y350304D01*
G01X750762Y336477D02*
X747010Y340229D01*
G01X746369Y339031D02*
X749462Y335938D01*
G01X750762Y333844D02*
Y336477D01*
G01X749462Y335938D02*
Y334383D01*
G01X748737Y331819D02*
X750762Y333844D01*
G01X749462Y334383D02*
X747816Y332737D01*
G01X749462Y334383D02*
X747816Y332737D01*
G01X748737Y331819D02*
X750762Y333844D01*
G01X749462Y335938D02*
Y334383D01*
G01X750762Y333844D02*
Y336477D01*
G01X746369Y339031D02*
X749462Y335938D01*
G01X750762Y336477D02*
X747010Y340229D01*
G01X752339Y349800D02*
X748285D01*
G01X751800Y348500D02*
X748414D01*
G01X755759Y346380D02*
X752339Y349800D01*
G01X754459Y345841D02*
X751800Y348500D01*
G01X755759Y343742D02*
Y346380D01*
G01X754459Y344281D02*
Y345841D01*
G01X754837Y342819D02*
X755759Y343742D01*
G01X753915Y343737D02*
X754459Y344281D01*
G01X751800Y348500D02*
X748414D01*
G01X752339Y349800D02*
X748285D01*
G01X754459Y345841D02*
X751800Y348500D01*
G01X755759Y346380D02*
X752339Y349800D01*
G01X754459Y344281D02*
Y345841D01*
G01X755759Y343742D02*
Y346380D01*
G01X753915Y343737D02*
X754459Y344281D01*
G01X754837Y342819D02*
X755759Y343742D01*
G01X755650Y352850D02*
X747929D01*
G01X755111Y351550D02*
X748056D01*
G01X769097Y339403D02*
X755650Y352850D01*
G01X767797Y338864D02*
X755111Y351550D01*
G01X769097Y333579D02*
Y339403D01*
G01X767797Y334118D02*
Y338864D01*
G01X766435Y330917D02*
X769097Y333579D01*
G01X766339Y332660D02*
X767797Y334118D01*
G01X765515Y331837D02*
X766339Y332661D01*
G01X755111Y351550D02*
X748056D01*
G01X755650Y352850D02*
X747929D01*
G01X767797Y338864D02*
X755111Y351550D01*
G01X769097Y339403D02*
X755650Y352850D01*
G01X767797Y334118D02*
Y338864D01*
G01X769097Y333579D02*
Y339403D01*
G01X766339Y332660D02*
X767797Y334118D01*
G01X766435Y330917D02*
X769097Y333579D01*
G01X765515Y331837D02*
X766339Y332661D01*
G01X766435Y330917D02*
X769097Y333579D01*
G01X763999Y356102D02*
X750215Y358858D01*
G01X763358Y354904D02*
X750215Y357532D01*
G01X763359Y354904D02*
X763358D01*
G01X766800Y353302D02*
X764117Y355985D01*
G01X765500Y352763D02*
X763359Y354904D01*
G01X766800Y350760D02*
Y353302D01*
G01X765500Y351299D02*
Y352763D01*
G01X765555Y349515D02*
X766800Y350760D01*
G01X764637Y350437D02*
X765499Y351299D01*
G01X763358Y354904D02*
X750215Y357532D01*
G01X763999Y356102D02*
X750215Y358858D01*
G01X763359Y354904D02*
X763358D01*
G01X763999Y356102D02*
X750215Y358858D01*
G01X765500Y352763D02*
X763359Y354904D01*
G01X766800Y353302D02*
X764117Y355985D01*
G01X765500Y351299D02*
Y352763D01*
G01X766800Y350760D02*
Y353302D01*
G01X764637Y350437D02*
X765499Y351299D01*
G01X765555Y349515D02*
X766800Y350760D01*
G01X780000Y339864D02*
X777653Y337517D01*
G01X777648Y339351D02*
X778700Y340403D01*
G01X776733Y338437D02*
X777648Y339352D01*
G01X780000Y344663D02*
Y339864D01*
G01X778700Y340403D02*
Y344124D01*
G01X765778Y358884D02*
X780000Y344663D01*
G01X765020Y357802D02*
X765019D01*
G01X778700Y344124D02*
X765020Y357802D01*
G01X749786Y362175D02*
X765660Y359000D01*
G01X765019Y357802D02*
X749786Y360849D01*
G01X765020Y357802D02*
X765019D01*
G01D02*
X749786Y360849D01*
G01Y362175D02*
X765660Y359000D01*
G01X765020Y357802D02*
X765019D01*
G01X765778Y358884D02*
X780000Y344663D01*
G01X749786Y362175D02*
X765660Y359000D01*
G01X778700Y344124D02*
X765020Y357802D01*
G01X765778Y358884D02*
X780000Y344663D01*
G01X778700Y340403D02*
Y344124D01*
G01X780000Y344663D02*
Y339864D01*
G01X777648Y339351D02*
X778700Y340403D01*
G01X780000Y339864D02*
X777653Y337517D01*
G01X776733Y338437D02*
X777648Y339352D01*
G01X780000Y339864D02*
X777653Y337517D01*
G01X820320Y330077D02*
X821265Y331022D01*
G01X820345Y331942D02*
X818403Y330000D01*
G01X818942Y328700D02*
X820320Y330078D01*
G01X820345Y331942D02*
X818403Y330000D01*
G01X813600Y328700D02*
X818942D01*
G01X818403Y330000D02*
X814139D01*
G01X811844Y330456D02*
X813600Y328700D01*
G01X814139Y330000D02*
X812964Y331175D01*
G01X810064Y335248D02*
X811844Y330456D01*
G01X810064Y335248D02*
X811844Y330456D01*
G01X814139Y330000D02*
X812964Y331175D01*
G01X811844Y330456D02*
X813600Y328700D01*
G01X818403Y330000D02*
X814139D01*
G01X813600Y328700D02*
X818942D01*
G01X820345Y331942D02*
X818403Y330000D01*
G01X820320Y330077D02*
X821265Y331022D01*
G01X818942Y328700D02*
X820320Y330078D01*
G01X812964Y331175D02*
X811439Y335282D01*
G01X811688Y340393D02*
X810064Y335248D01*
G01X811439Y335282D02*
X813036Y340343D01*
G01X807679Y357356D02*
X811688Y340393D01*
G01X813036Y340343D02*
X808889Y357893D01*
G01X802428Y364988D02*
X807679Y357356D01*
G01X808889Y357893D02*
X803353Y365939D01*
G01X808889Y357893D02*
X803353Y365939D01*
G01X802428Y364988D02*
X807679Y357356D01*
G01X813036Y340343D02*
X808889Y357893D01*
G01X807679Y357356D02*
X811688Y340393D01*
G01X811439Y335282D02*
X813036Y340343D01*
G01X811688Y340393D02*
X810064Y335248D01*
G01X812964Y331175D02*
X811439Y335282D01*
G01X806200Y337084D02*
Y351405D01*
G01X804900Y337623D02*
Y350866D01*
G01X805386Y336270D02*
X806200Y337084D01*
G01X803917Y336640D02*
X804900Y337623D01*
G01X804837Y335720D02*
X805387Y336270D01*
G01X803917Y336640D02*
X804900Y337623D01*
G01D02*
Y350866D01*
G01X806200Y337084D02*
Y351405D01*
G01X803917Y336640D02*
X804900Y337623D01*
G01X805386Y336270D02*
X806200Y337084D01*
G01X804837Y335720D02*
X805387Y336270D01*
M02*
